# GT_SWB_BOM_20230503.xlsx — SWB_BOM (bom)
| Description | Manuf_name | Manuf_PN | Quantity | Part Reference | ROOM |
| CAP CHIP 0.22UF 6.3V(+-10%,X6S,0201)_DIFF BUS | MURATA ERIE N.A. INC TAIWAN BRANCH Okayama Murata Mfg.Co.,Ltd.Wakura Murata Mfg. | GRM033C80J224K | 900 | C1,C2,C3,C4,C5,C6,C7,C8,C9,C10,C11,C12,C13,C14,C15,C16,C17,C18,C19,C20,C21,C22,C23,C24,C25,C26,C27,C28,C29,C30,C31,C32,C33,C34,C35,C36,C37,C38,C39,C40,C41,C42,C43,C44,C45,C46,C47,C48,C49,C50,C51,C52,C53,C54,C55,C56,C57,C58,C59,C60,C61,C62,C63,C64,C65,C66,C67,C68,C69,C70,C71,C72,C73,C74,C75,C76,C77,C78,C79,C80,C81,C82,C83,C84,C85,C86,C87,C88,C89,C90,C91,C92,C93,C94,C95,C96,C97,C98,C99,C100,C101,C102,C103,C104,C105,C106,C107,C108,C109,C110,C111,C112,C113,C114,C115,C116,C117,C118,C119,C120,C121,C122,C123,C124,C125,C126,C127,C128,C129,C130,C131,C132,C133,C134,C135,C136,C137,C138,C139,C140,C141,C142,C143,C144,C145,C146,C147,C148,C149,C150,C151,C152,C153,C154,C155,C156,C157,C158,C159,C160,C161,C162,C163,C164,C165,C166,C167,C168,C169,C170,C171,C172,C173,C174,C175,C176,C177,C178,C179,C180,C181,C182,C183,C184,C185,C186,C187,C188,C189,C190,C191,C192,C212,C213,C214,C215,C216,C217,C218,C219,C220,C221,C222,C223,C224,C225,C226,C227,C228,C229,C230,C231,C232,C233,C234,C235,C236,C237,C238,C239,C240,C241,C242,C243,C244,C245,C246,C247,C248,C249,C250,C251,C252,C253,C254,C255,C256,C257,C258,C259,C260,C261,C262,C263,C264,C265,C266,C267,C268,C269,C270,C271,C272,C273,C274,C275,C276,C277,C278,C279,C280,C281,C282,C283,C284,C285,C286,C287,C288,C289,C290,C291,C292,C293,C294,C295,C296,C297,C298,C299,C300,C301,C302,C303,C304,C305,C306,C307,C340,C341,C342,C343,C344,C345,C346,C347,C348,C349,C350,C351,C352,C353,C354,C355,C356,C357,C358,C359,C360,C361,C362,C363,C364,C365,C366,C367,C368,C369,C370,C371,C372,C373,C374,C375,C376,C377,C378,C379,C380,C381,C382,C383,C384,C385,C386,C387,C388,C389,C390,C391,C392,C393,C394,C395,C396,C397,C398,C399,C400,C401,C402,C403,C423,C424,C425,C426,C427,C428,C429,C430,C431,C432,C433,C434,C435,C436,C437,C438,C439,C440,C441,C442,C443,C444,C445,C446,C447,C448,C449,C450,C451,C452,C453,C454,C455,C456,C457,C458,C459,C460,C461,C462,C463,C464,C465,C466,C467,C468,C469,C470,C471,C472,C473,C474,C475,C476,C477,C478,C479,C480,C481,C482,C483,C484,C485,C486,C487,C488,C489,C490,C491,C492,C493,C494,C495,C496,C497,C498,C499,C500,C501,C502,C503,C504,C505,C506,C507,C508,C509,C510,C511,C512,C513,C514,C515,C516,C517,C518,C519,C520,C521,C522,C523,C524,C525,C526,C527,C528,C529,C530,C531,C532,C533,C534,C535,C536,C537,C538,C539,C540,C541,C542,C543,C544,C545,C546,C547,C548,C549,C550,C551,C552,C553,C554,C555,C556,C557,C558,C559,C560,C561,C562,C563,C564,C565,C566,C567,C568,C569,C570,C571,C572,C573,C574,C575,C576,C577,C578,C579,C580,C581,C582,C583,C584,C585,C586,C587,C588,C589,C590,C591,C592,C593,C594,C595,C596,C597,C598,C599,C600,C601,C602,C603,C604,C605,C606,C607,C608,C609,C610,C611,C612,C613,C614,C634,C635,C636,C637,C638,C639,C640,C641,C642,C643,C644,C645,C646,C647,C648,C649,C650,C651,C652,C653,C654,C655,C656,C657,C658,C659,C660,C661,C662,C663,C664,C665,C666,C667,C668,C669,C670,C671,C672,C673,C674,C675,C676,C677,C678,C679,C680,C681,C682,C683,C684,C685,C686,C687,C688,C689,C690,C691,C692,C693,C694,C695,C696,C697,C698,C699,C700,C701,C702,C703,C704,C705,C706,C707,C708,C709,C710,C711,C712,C713,C714,C715,C716,C717,C718,C719,C720,C721,C722,C723,C724,C725,C726,C727,C728,C729,C730,C731,C732,C733,C734,C735,C736,C737,C738,C739,C740,C741,C742,C743,C744,C745,C746,C747,C748,C749,C750,C751,C752,C753,C754,C755,C756,C757,C758,C759,C760,C761,C762,C763,C764,C765,C766,C767,C768,C769,C770,C771,C772,C773,C774,C775,C776,C777,C778,C779,C780,C781,C782,C783,C784,C785,C786,C787,C788,C789,C790,C791,C792,C793,C794,C795,C796,C797,C798,C799,C800,C801,C802,C803,C804,C805,C806,C807,C808,C809,C810,C811,C812,C813,C814,C815,C816,C817,C818,C819,C820,C821,C822,C823,C824,C825,C2152,C2153,C2154,C2155,C2156,C2157,C2158,C2159,C2160,C2161,C2162,C2163,C2164,C2165,C2166,C2167,C2168,C2169,C2170,C2171,C2172,C2173,C2174,C2175,C2176,C2177,C2178,C2179,C2180,C2181,C2182,C2183,C2243,C2244,C2245,C2246,C2247,C2248,C2249,C2250,C2251,C2252,C2253,C2254,C2255,C2256,C2257,C2258,C2259,C2260,C2261,C2262,C2263,C2264,C2265,C2266,C2267,C2268,C2269,C2270,C2271,C2272,C2273,C2274,C2341,C2342,C2343,C2344,C2345,C2346,C2347,C2348,C2349,C2350,C2351,C2352,C2353,C2354,C2355,C2356,C2357,C2358,C2359,C2360,C2361,C2362,C2363,C2364,C2365,C2366,C2367,C2368,C2369,C2370,C2371,C2372,C2439,C2440,C2441,C2442,C2443,C2444,C2445,C2446,C2447,C2448,C2449,C2450,C2451,C2452,C2453,C2454,C2455,C2456,C2457,C2458,C2459,C2460,C2461,C2462,C2463,C2464,C2465,C2466,C2467,C2468,C2469,C2470,C2512,C2513,C2514,C2515,C2516,C2517,C2518,C2519,C2520,C2521,C2522,C2523,C2524,C2525,C2526,C2527,C2528,C2529,C2530,C2531,C2532,C2533,C2534,C2535,C2536,C2537,C2538,C2539,C2540,C2541,C2542,C2543,C3984,C3985,C3986,C3987 |  |
| CAP CHIP 0.1U 25V(+-10%,X7R,0402) | YAGEO CORPORATION | CC0402KRX7R8BB104 | 187 | C193,C194,C195,C196,C202,C203,C205,C206,C208,C209,C211,C308,C310,C311,C313,C314,C316,C317,C319,C320,C322,C323,C325,C326,C328,C329,C331,C332,C334,C335,C337,C338,C404,C405,C407,C408,C410,C411,C413,C414,C416,C417,C419,C420,C422,C615,C617,C618,C620,C621,C623,C624,C626,C627,C629,C630,C632,C633,C827,C828,C830,C831,C2185,C2494,C2615,C2616,C2618,C2619,C2620,C2658,C2659,C2660,C2661,C2744,C2745,C2746,C2747,C2763,C2764,C2765,C2766,C2767,C2768,C2769,C2770,C2771,C2772,C2773,C2774,C2775,C2776,C2777,C2778,C2851,C3609,C3625,C3626,C3649,C3869,C3998,C3999,C4000,C4001,C4002,C4003,C4004,C4005,C4006,C4417,C4422,C4427,C4432,C4434,C4435,C4436,C4437,PC17,PC18,PC22,PC23,PC31,PC36,PC42,PC54,PC56,PC58,PC67,PC73,PC75,PC83,PC89,PC91,PC100,PC106,PC108,PC116,PC122,PC134,PC136,PC138,PC147,PC153,PC156,PC163,PC166,PC171,PC180,PC186,PC188,PC196,PC202,PC203,PC211,PC216,PC222,PC223,PC231,PC236,PC242,PC243,PC251,PC256,PC262,PC264,PC271,PC276,PC282,PC283,PC289,PC290,PC296,PC603,PC607,PC620,PC627,PC803,PC807,PC820,PC827,PC978,PC979,PC980,PC981,PC982,PC983,PC984,PC985 |  |
| CAP CHIP 0.1U 16V(10%.X7R.0402) | MURATA ERIE N.A. INC TAIWAN BRANCH Okayama Murata Mfg.Co..Ltd. Wakura Murata Mfg | WBM155R71C104K | 137 | C198,C2093,C2095,C2096,C2108,C2109,C2110,C2146,C2147,C2216,C2217,C2307,C2308,C2405,C2406,C2503,C2504,C2555,C2556,C2569,C2570,C2571,C2604,C2605,C2606,C2607,C2608,C2609,C2610,C2611,C2612,C2613,C2625,C2626,C2627,C2628,C2629,C2663,C2664,C2665,C2666,C2667,C2668,C2669,C2671,C2672,C2674,C2675,C2676,C2677,C2678,C2679,C2680,C2682,C2683,C2704,C2705,C2706,C2707,C2708,C2709,C2710,C2711,C2712,C2713,C2714,C2715,C2716,C2717,C2718,C2719,C2720,C2721,C2722,C2723,C2724,C2725,C2726,C2727,C2728,C2729,C2730,C2731,C2732,C2733,C2734,C2735,C2736,C2737,C2738,C2739,C2740,C2741,C2742,C2743,C2748,C2754,C2755,C2756,C2757,C2758,C2759,C2760,C2761,C2779,C2780,C2781,C2782,C2783,C2784,C2808,C2809,C2811,C2841,C2846,C3644,C3645,C3646,C3652,C3653,C3870,C3871,C3988,C3989,C3992,C3993,C3994,C3995,C4185,C4186,C4187,C4188,C4189,C4448,C4449,C4450,C4451 |  |
| CAP CHIP 1000P 50V(+-5%.X7R.0402) | ACER PERIPHERALS INC.(Darfon Electronics Corp.) | C1005X7R102JGT | 5 | C200,C832,C835,C836,C838 |  |
| CAP CHIP 0.1U 25V(+-10%,X7R,0402) | YAGEO CORPORATION | CC0402KRX7R8BB104 | 248 | C201,C204,C207,C210,C309,C312,C315,C318,C321,C324,C327,C330,C333,C336,C339,C406,C409,C412,C415,C418,C421,C616,C619,C622,C625,C628,C631,C826,C829,C852,C853,C854,C855,C856,C857,C858,C859,C867,C868,C869,C870,C871,C872,C873,C874,C882,C883,C884,C885,C886,C887,C888,C889,C897,C898,C899,C900,C901,C902,C903,C904,C912,C913,C914,C915,C916,C917,C918,C919,C927,C928,C929,C930,C931,C932,C933,C934,C942,C943,C944,C945,C946,C947,C948,C949,C957,C958,C959,C960,C961,C962,C963,C964,C965,C966,C967,C968,C969,C970,C971,C972,C973,C974,C975,C976,C977,C978,C979,C980,C2654,C2656,C2696,C2697,C2698,C2699,C2700,C2702,C2703,C2842,C3620,C3657,C3661,C3662,C3663,C3664,C3665,C3666,C3667,C3668,C3669,C3670,C3671,C3672,C3673,C3674,C3675,C3676,C3872,C3873,C3874,C3875,C3876,C3877,C3880,C3881,C3882,C3883,C3884,C3885,C3887,C3888,C3889,C3890,C3891,C3892,C3894,C3895,C3896,C3897,C3898,C3899,C3901,C3902,C3903,C3904,C3905,C3906,C3908,C3909,C3910,C3911,C3912,C3913,C3915,C3916,C3917,C3918,C3919,C3920,C3922,C3923,C3924,C3925,C3926,C3927,C3929,C3930,C3931,C3932,C3933,C3934,C3936,C3937,C3938,C3939,C3940,C3941,C3943,C3944,C3945,C3946,C3947,C3948,C3950,C3951,C3952,C3953,C3954,C3955,C3957,C3958,C3959,C3960,C3961,C3962,C3964,C3965,C3966,C3967,C3968,C3969,C3971,C3972,C3973,C3974,C3975,C3976,C3978,C3979,C3980,C3981,C3982,C3983,C4177,C4178,C4179,C4180,C4181,C4183,C4184,C4494,C4495,C4496,C4497,C4498,C4499,C4500,C4501 |  |
| CAP CHIP 22UF 16V(+-20%,X6S,0805)MUR | MURATA ERIE N.A. INC TAIWAN BRANCH Okayama Murata | GRM21BC81C226M | 110 | C845,C846,C860,C861,C875,C876,C890,C891,C905,C906,C920,C921,C935,C936,C950,C951,C4416,C4421,C4426,C4431,PC20,PC21,PC26,PC27,PC28,PC29,PC32,PC33,PC34,PC35,PC60,PC61,PC62,PC63,PC77,PC78,PC79,PC80,PC93,PC94,PC95,PC96,PC110,PC111,PC112,PC114,PC140,PC141,PC142,PC143,PC158,PC159,PC160,PC161,PC173,PC174,PC175,PC176,PC190,PC191,PC192,PC193,PC204,PC205,PC206,PC207,PC208,PC209,PC224,PC225,PC226,PC227,PC228,PC229,PC244,PC245,PC246,PC247,PC249,PC250,PC263,PC265,PC266,PC267,PC268,PC269,PC284,PC285,PC286,PC287,PC1007,PC1008,PC1009,PC1010,PC6607,PC6608,PC6609,PC6610,PC6611,PC6612,PC6613,PC6614,PC6615,PC6616,PC6617,PC6618,PC6619,PC6620,PC6621,PC6622 |  |
| CAP CHIP 0.1UF 16V(+-10%,X6S,0201) | TAIYO YUDEN CO.,LTD | EMK063AC6104KP-F | 40 | C847,C848,C849,C850,C851,C862,C863,C864,C865,C866,C877,C878,C879,C880,C881,C892,C893,C894,C895,C896,C907,C908,C909,C910,C911,C922,C923,C924,C925,C926,C937,C938,C939,C940,C941,C952,C953,C954,C955,C956 |  |
| CAP CHIP 10U 6.3V(+-20%,X6S,0603) | MURATA ERIE N.A. INC TAIWAN BRANCH Okayama Murata Mfg.Co., | GRM188C80J106M | 108 | C1100,C1101,C1102,C1157,C1158,C1159,C1160,C1355,C1356,C1357,C1412,C1413,C1414,C1415,C1610,C1611,C1612,C1667,C1668,C1669,C1670,C1865,C1866,C1867,C1922,C1923,C1924,C1925,C2630,C2634,C2638,C2642,C2644,C2650,C2653,C2655,C2657,C2785,C2789,C2793,C2797,C2799,C2805,C2902,C2903,C2944,C2945,C2988,C2990,C3021,C3024,C3027,C3039,C3042,C3045,C3055,C3058,C3067,C3070,C3075,C3082,C3118,C3119,C3161,C3163,C3195,C3198,C3201,C3213,C3216,C3219,C3229,C3232,C3241,C3244,C3249,C3253,C3292,C3293,C3336,C3338,C3369,C3372,C3375,C3387,C3390,C3393,C3403,C3406,C3415,C3418,C3423,C3424,C3466,C3467,C3510,C3512,C3543,C3546,C3549,C3561,C3564,C3567,C3577,C3580,C3589,C3592,C3991 |  |
| CAP CHIP 1U 4V(+-20%,X6S,0201) | TAIYO YUDEN CO.,LTD | AMK063AC6105MP-F | 232 | C1103,C1104,C1105,C1106,C1161,C1162,C1163,C1164,C1165,C1166,C1358,C1359,C1360,C1361,C1416,C1417,C1418,C1419,C1420,C1421,C1613,C1614,C1615,C1616,C1671,C1672,C1673,C1674,C1675,C1676,C1868,C1869,C1870,C1871,C1926,C1927,C1928,C1929,C1930,C1931,C2904,C2905,C2906,C2907,C2908,C2946,C2947,C2948,C2949,C2950,C2987,C2989,C3016,C3018,C3020,C3022,C3025,C3028,C3034,C3036,C3038,C3040,C3043,C3046,C3052,C3054,C3056,C3059,C3064,C3066,C3068,C3071,C3076,C3083,C3084,C3085,C3086,C3120,C3121,C3122,C3123,C3124,C3162,C3164,C3190,C3192,C3194,C3196,C3199,C3202,C3208,C3210,C3212,C3214,C3217,C3220,C3226,C3228,C3230,C3233,C3238,C3240,C3242,C3245,C3250,C3251,C3254,C3255,C3256,C3294,C3295,C3296,C3297,C3298,C3335,C3337,C3364,C3366,C3368,C3370,C3373,C3376,C3382,C3384,C3386,C3388,C3391,C3394,C3400,C3402,C3404,C3407,C3412,C3414,C3416,C3419,C3425,C3426,C3427,C3428,C3429,C3468,C3469,C3470,C3471,C3472,C3509,C3511,C3538,C3540,C3542,C3544,C3547,C3550,C3556,C3558,C3560,C3562,C3565,C3568,C3574,C3576,C3578,C3581,C3586,C3588,C3590,C3593,C4190,C4195,C4200,C4201,C4208,C4209,C4210,C4211,C4222,C4223,C4224,C4225,C4236,C4237,C4238,C4239,C4250,C4251,C4252,C4253,C4264,C4265,C4266,C4267,C4278,C4279,C4280,C4281,C4292,C4293,C4294,C4295,C4306,C4307,C4308,C4309,C4320,C4321,C4322,C4323,C4334,C4335,C4336,C4337,C4348,C4349,C4350,C4351,C4362,C4363,C4364,C4365,C4376,C4377,C4378,C4379,C4390,C4391,C4392,C4393,C4404,C4405,C4406,C4407 |  |
| CAP CHIP 1000P 16V(+-5%,X7R,0201) | MURATA ERIE N.A. INC TAIWAN BRANCH Okayama Murata Mfg.Co.,Ltd.Wakura Murata Mfg. Co., Ltd. | GRM033R71C102J | 308 | C1107,C1108,C1109,C1110,C1111,C1112,C1113,C1123,C1124,C1125,C1126,C1127,C1128,C1129,C1130,C1131,C1132,C1167,C1168,C1169,C1170,C1171,C1172,C1173,C1174,C1175,C1176,C1177,C1178,C1179,C1180,C1181,C1182,C1183,C1184,C1185,C1186,C1187,C1188,C1189,C1190,C1191,C1192,C1193,C1194,C1195,C1196,C1362,C1363,C1364,C1365,C1366,C1367,C1368,C1369,C1370,C1371,C1372,C1373,C1374,C1375,C1391,C1392,C1393,C1422,C1423,C1424,C1425,C1426,C1427,C1428,C1429,C1430,C1431,C1432,C1433,C1434,C1435,C1436,C1437,C1438,C1439,C1440,C1441,C1442,C1443,C1444,C1445,C1446,C1447,C1448,C1449,C1450,C1451,C1617,C1618,C1619,C1626,C1627,C1628,C1629,C1630,C1631,C1632,C1633,C1634,C1635,C1636,C1637,C1638,C1639,C1677,C1678,C1679,C1680,C1681,C1682,C1683,C1684,C1685,C1686,C1687,C1688,C1689,C1690,C1691,C1692,C1693,C1694,C1695,C1696,C1697,C1698,C1699,C1700,C1701,C1702,C1703,C1704,C1705,C1706,C1872,C1873,C1874,C1875,C1876,C1877,C1878,C1888,C1889,C1890,C1891,C1892,C1893,C1894,C1895,C1896,C1897,C1932,C1933,C1934,C1935,C1936,C1937,C1938,C1939,C1940,C1941,C1942,C1943,C1944,C1945,C1946,C1947,C1948,C1949,C1950,C1951,C1952,C1953,C1954,C1955,C1956,C1957,C1958,C1959,C1960,C1961,C2901,C2909,C2910,C2911,C2912,C2913,C2914,C2915,C2916,C2917,C2918,C2951,C2952,C2953,C2954,C2955,C2956,C2957,C2958,C2959,C2960,C2961,C2991,C2992,C2993,C2994,C2995,C2996,C2997,C2998,C3077,C3078,C3079,C3080,C3081,C3087,C3088,C3089,C3090,C3091,C3092,C3125,C3126,C3127,C3128,C3129,C3130,C3131,C3132,C3133,C3134,C3135,C3165,C3166,C3167,C3168,C3169,C3170,C3171,C3172,C3252,C3257,C3258,C3259,C3260,C3261,C3262,C3263,C3264,C3265,C3266,C3299,C3300,C3301,C3302,C3303,C3304,C3305,C3306,C3307,C3308,C3309,C3339,C3340,C3341,C3342,C3343,C3344,C3345,C3346,C3430,C3431,C3432,C3433,C3434,C3435,C3436,C3437,C3438,C3439,C3440,C3473,C3474,C3475,C3476,C3477,C3478,C3479,C3480,C3481,C3482,C3483,C3513,C3514,C3515,C3516,C3517,C3518,C3519,C3520 |  |
| CAP CHIP 0.1UF 6.3V(10%,X6S,0201)TAY | TAIYO YUDEN CO.,LTD | JMK063C6104KP-F | 612 | C1114,C1115,C1116,C1117,C1118,C1119,C1120,C1121,C1122,C1133,C1134,C1135,C1136,C1137,C1138,C1139,C1140,C1141,C1142,C1143,C1144,C1145,C1146,C1147,C1148,C1149,C1150,C1151,C1152,C1153,C1154,C1155,C1156,C1197,C1198,C1199,C1200,C1201,C1202,C1203,C1204,C1205,C1206,C1207,C1208,C1209,C1210,C1211,C1212,C1213,C1214,C1215,C1216,C1217,C1218,C1219,C1220,C1221,C1222,C1223,C1224,C1225,C1226,C1227,C1228,C1229,C1230,C1231,C1232,C1233,C1234,C1235,C1236,C1237,C1238,C1239,C1240,C1376,C1377,C1378,C1379,C1380,C1381,C1382,C1383,C1384,C1385,C1386,C1387,C1388,C1389,C1390,C1394,C1395,C1396,C1397,C1398,C1399,C1400,C1401,C1402,C1403,C1404,C1405,C1406,C1407,C1408,C1409,C1410,C1411,C1452,C1453,C1454,C1455,C1456,C1457,C1458,C1459,C1460,C1461,C1462,C1463,C1464,C1465,C1466,C1467,C1468,C1469,C1470,C1471,C1472,C1473,C1474,C1475,C1476,C1477,C1478,C1479,C1480,C1481,C1482,C1483,C1484,C1485,C1486,C1487,C1488,C1489,C1490,C1491,C1492,C1493,C1494,C1495,C1620,C1621,C1622,C1623,C1624,C1625,C1640,C1641,C1642,C1643,C1644,C1645,C1646,C1647,C1648,C1649,C1650,C1651,C1652,C1653,C1654,C1655,C1656,C1657,C1658,C1659,C1660,C1661,C1662,C1663,C1664,C1665,C1666,C1707,C1708,C1709,C1710,C1711,C1712,C1713,C1714,C1715,C1716,C1717,C1718,C1719,C1720,C1721,C1722,C1723,C1724,C1725,C1726,C1727,C1728,C1729,C1730,C1731,C1732,C1733,C1734,C1735,C1736,C1737,C1738,C1739,C1740,C1741,C1742,C1743,C1744,C1745,C1746,C1747,C1748,C1749,C1750,C1879,C1880,C1881,C1882,C1883,C1884,C1885,C1886,C1887,C1898,C1899,C1900,C1901,C1902,C1903,C1904,C1905,C1906,C1907,C1908,C1909,C1910,C1911,C1912,C1913,C1914,C1915,C1916,C1917,C1918,C1919,C1920,C1921,C1962,C1963,C1964,C1965,C1966,C1967,C1968,C1969,C1970,C1971,C1972,C1973,C1974,C1975,C1976,C1977,C1978,C1979,C1980,C1981,C1982,C1983,C1984,C1985,C1986,C1987,C1988,C1989,C1990,C1991,C1992,C1993,C1994,C1995,C1996,C1997,C1998,C1999,C2000,C2001,C2002,C2003,C2004,C2005,C2919,C2920,C2921,C2922,C2923,C2924,C2925,C2926,C2927,C2928,C2929,C2930,C2931,C2932,C2933,C2934,C2935,C2936,C2937,C2938,C2939,C2940,C2941,C2942,C2943,C2962,C2963,C2964,C2965,C2966,C2967,C2968,C2969,C2970,C2971,C2972,C2973,C2974,C2975,C2976,C2977,C2978,C2979,C2980,C2981,C2982,C2983,C2984,C2985,C2986,C2999,C3000,C3001,C3002,C3003,C3004,C3005,C3006,C3007,C3008,C3009,C3010,C3011,C3012,C3013,C3014,C3023,C3026,C3029,C3041,C3044,C3047,C3057,C3060,C3069,C3072,C3093,C3094,C3095,C3096,C3097,C3098,C3099,C3100,C3101,C3102,C3103,C3104,C3105,C3106,C3107,C3108,C3109,C3110,C3111,C3112,C3113,C3114,C3115,C3116,C3117,C3136,C3137,C3138,C3139,C3140,C3141,C3142,C3143,C3144,C3145,C3146,C3147,C3148,C3149,C3150,C3151,C3152,C3153,C3154,C3155,C3156,C3157,C3158,C3159,C3160,C3173,C3174,C3175,C3176,C3177,C3178,C3179,C3180,C3181,C3182,C3183,C3184,C3185,C3186,C3187,C3188,C3197,C3200,C3203,C3215,C3218,C3221,C3231,C3234,C3243,C3246,C3267,C3268,C3269,C3270,C3271,C3272,C3273,C3274,C3275,C3276,C3277,C3278,C3279,C3280,C3281,C3282,C3283,C3284,C3285,C3286,C3287,C3288,C3289,C3290,C3291,C3310,C3311,C3312,C3313,C3314,C3315,C3316,C3317,C3318,C3319,C3320,C3321,C3322,C3323,C3324,C3325,C3326,C3327,C3328,C3329,C3330,C3331,C3332,C3333,C3334,C3347,C3348,C3349,C3350,C3351,C3352,C3353,C3354,C3355,C3356,C3357,C3358,C3359,C3360,C3361,C3362,C3371,C3374,C3377,C3389,C3392,C3395,C3405,C3408,C3417,C3420,C3441,C3442,C3443,C3444,C3445,C3446,C3447,C3448,C3449,C3450,C3451,C3452,C3453,C3454,C3455,C3456,C3457,C3458,C3459,C3460,C3461,C3462,C3463,C3464,C3465,C3484,C3485,C3486,C3487,C3488,C3489,C3490,C3491,C3492,C3493,C3494,C3495,C3496,C3497,C3498,C3499,C3500,C3501,C3502,C3503,C3504,C3505,C3506,C3507,C3508,C3521,C3522,C3523,C3524,C3525,C3526,C3527,C3528,C3529,C3530,C3531,C3532,C3533,C3534,C3535,C3536,C3545,C3548,C3551,C3563,C3566,C3569,C3579,C3582,C3591,C3594 |  |
| CAP CHIP 0.1U 16V(10%.X7R.0402)_OCTAGON | MURATA ERIE N.A. INC TAIWAN BRANCH Okayama Murata Mfg.Co..Ltd. Wakura Murata Mfg | WBM155R71C104K | 28 | C2006,C2007,C2008,C2013,C2017,C2018,C2021,C2025,C2028,C2029,C2040,C2041,C2051,C2052,C2062,C2063,C2074,C2076,C2081,C2086,C3605,C3607,C3610,C3612,C3613,C3622,C3623,C3624 |  |
| CAP CHIP 1UF 25V(+-10%,X6S,0402)_OCTAGON | MURATA ERIE N.A. INC TAIWAN BRANCH Okayama Murata Mfg.Co..Ltd.Wakura Murata Mfg. | GRM155C81E105K | 11 | C2009,C2014,C2019,C2022,C2023,C2024,C2026,C2027,C3606,C3608,C3611 |  |
| CAP CHIP 22U 6.3V(+-20%,X6S,0603)SAM | SAMSUNG ELECTRONICS CO.,LTD (Samsung Mobile Display)SAMSUNG SDI CO.,LTD | CL10X226MQ8QRWE | 62 | C2010,C2011,C2012,C2015,C2016,C2020,C3015,C3017,C3019,C3033,C3035,C3037,C3051,C3053,C3063,C3065,C3189,C3191,C3193,C3207,C3209,C3211,C3225,C3227,C3237,C3239,C3363,C3365,C3367,C3381,C3383,C3385,C3399,C3401,C3411,C3413,C3537,C3539,C3541,C3555,C3557,C3559,C3573,C3575,C3585,C3587,C4206,C4207,C4216,C4217,C4258,C4259,C4272,C4273,C4314,C4315,C4328,C4329,C4370,C4371,C4384,C4385 |  |
| CAP CHIP 0.01U 25V(+-10%.X7R.0402)_OCTAGON | ACER PERIPHERALS INC.(Darfon Electronics Corp.) | C1005X7R103KFT | 49 | C2030,C2031,C2032,C2033,C2034,C2035,C2036,C2037,C2042,C2043,C2044,C2045,C2046,C2047,C2048,C2049,C2053,C2054,C2055,C2056,C2057,C2058,C2059,C2060,C2064,C2065,C2066,C2067,C2068,C2069,C2070,C2071,C2072,C2073,C2077,C2078,C2079,C2082,C2083,C2084,C2087,C2088,C2089,C3614,C3615,C3616,C3617,C3618,C3619 |  |
| CAP CHIP 10UF 6.3V(+-20%,X6S,0402)_OCTAGON | MURATA ERIE N.A. INC TAIWAN BRANCH Okayama Murata Mfg.Co., | GRM155C80J106M | 7 | C2038,C2039,C2050,C2061,C2075,C2080,C2085 |  |
| CAP CHIP 1UF 25V(+-10%,X6S,0402) | MURATA ERIE N.A. INC TAIWAN BRANCH Okayama Murata Mfg.Co..Ltd.Wakura Murata Mfg. | GRM155C81E105K | 104 | C2145,C2491,C2617,C2621,C2624,C2631,C2639,C2645,C2786,C2794,C2800,C2848,C3621,C3878,C3879,C3886,C3893,C3900,C3907,C3914,C3921,C3928,C3935,C3942,C3949,C3956,C3963,C3970,C3977,C4414,C4419,C4424,C4429,PC30,PC40,PC45,PC59,PC76,PC92,PC109,PC126,PC139,PC157,PC172,PC189,PC210,PC220,PC230,PC237,PC248,PC257,PC270,PC277,PC288,PC295,PC593,PC598,PC599,PC618,PC619,PC638,PC639,PC648,PC649,PC658,PC659,PC668,PC669,PC678,PC679,PC788,PC789,PC798,PC799,PC818,PC821,PC838,PC839,PC848,PC849,PC858,PC859,PC868,PC869,PC878,PC879,PC888,PC889,PC898,PC899,PC908,PC909,PC918,PC919,PC928,PC929,PC938,PC939,PC948,PC949,PC958,PC959,PC968,PC969 |  |
| CAP CHIP 10UF 6.3V(+-20%,X6S,0402) | MURATA ERIE N.A. INC TAIWAN BRANCH Okayama Murata Mfg.Co., | GRM155C80J106M | 1 | C2614 |  |
| CAP CHIP 18P 50V(+-5% C0G 0402) | MURATA ERIE N.A. INC TAIWAN BRANCH Okayama Murata Mfg.Co..Ltd. Wakura Murata Mfg | GRM1555C1H180J | 4 | C2622,C2623,C3635,C3636 |  |
| CAP CHIP 0.047U 25V(+-10% X7R 0402) | MURATA ERIE N.A. INC TAIWAN BRANCH Okayama Murata Mfg.Co.,Ltd.Wakura Murata Mfg. | GRM155R71E473K | 23 | C2632,C2633,C2635,C2640,C2641,C2643,C2646,C2647,C2648,C2649,C2651,C2787,C2788,C2790,C2795,C2796,C2798,C2801,C2802,C2803,C2804,C2806,C3647 |  |
| CAP CHIP 8.2P 50V (+-0.1P NP0 0402) | PHYCOMP TAIWAN LTD.(YAGEO) | 2238 869 18828 | 2 | C2636,C2791 |  |
| CAP CHIP 10P 50V(+-2%,NPO,0402) | YAGEO CORPORATION | CC0402GRNPO9BN100 | 2 | C2637,C2792 |  |
| CAP CHIP 10UF 16V(+-10%,X7R,0805) | SAMSUNG ELECTRONICS CO.,LTD | CL21B106KOQNNNE | 8 | C2662,C2673,C2849,C2850,C4415,C4420,C4425,C4430 |  |
| CAP CHIP 1U 10V(+-10%.X7R.0603) | WALSIN TECHNOLOGY CORPORATION | 0603B105K100CT | 2 | C2670,C2681 |  |
| CAP CHIP 10U 25V(+-10%,X6S,0805)MUR | MURATA ERIE N.A. INC TAIWAN BRANCH Okayama Murata Mfg.Co.,Ltd.Wakura Murata Mfg. | GRM21BC81E106K | 72 | C2695,C2701,C4176,C4182,PC16,PC46,PC127,PC323,PC335,PC345,PC347,PC369,PC381,PC395,PC405,PC429,PC431,PC443,PC595,PC600,PC601,PC602,PC604,PC605,PC606,PC621,PC622,PC623,PC624,PC625,PC643,PC655,PC661,PC663,PC671,PC673,PC681,PC683,PC791,PC793,PC800,PC801,PC802,PC804,PC805,PC822,PC823,PC824,PC826,PC841,PC844,PC854,PC864,PC876,PC883,PC886,PC901,PC903,PC911,PC913,PC921,PC923,PC931,PC933,PC941,PC943,PC951,PC953,PC962,PC966,PC972,PC976 |  |
| CAP CHIP 0.1U 25V(+-10%,X7R,0402) | YAGEO CORPORATION | CC0402KRX7R8BB104 | 1 | C2844 | COMP_BOM1 |
| CAP CHIP 47U 2.5V(+-20%,X6S,0603) | MURATA ERIE N.A. INC TAIWAN BRANCH Okayama Murata Mfg.Co.,Ltd.Wakura Murata Mfg. Co., Ltd. (Peregrine Semiconductor Corp | GRM188C80E476M | 168 | C3030,C3031,C3032,C3048,C3049,C3050,C3061,C3062,C3073,C3074,C3204,C3205,C3206,C3222,C3223,C3224,C3235,C3236,C3247,C3248,C3378,C3379,C3380,C3396,C3397,C3398,C3409,C3410,C3421,C3422,C3552,C3553,C3554,C3570,C3571,C3572,C3583,C3584,C3595,C3596,C4191,C4192,C4193,C4194,C4196,C4197,C4198,C4199,C4202,C4203,C4204,C4205,C4212,C4213,C4214,C4215,C4218,C4219,C4220,C4221,C4226,C4227,C4228,C4229,C4232,C4233,C4234,C4235,C4240,C4241,C4242,C4243,C4246,C4247,C4248,C4249,C4254,C4255,C4256,C4257,C4260,C4261,C4262,C4263,C4268,C4269,C4270,C4271,C4274,C4275,C4276,C4277,C4282,C4283,C4284,C4285,C4288,C4289,C4290,C4291,C4296,C4297,C4298,C4299,C4302,C4303,C4304,C4305,C4310,C4311,C4312,C4313,C4316,C4317,C4318,C4319,C4324,C4325,C4326,C4327,C4330,C4331,C4332,C4333,C4338,C4339,C4340,C4341,C4344,C4345,C4346,C4347,C4352,C4353,C4354,C4355,C4358,C4359,C4360,C4361,C4366,C4367,C4368,C4369,C4372,C4373,C4374,C4375,C4380,C4381,C4382,C4383,C4386,C4387,C4388,C4389,C4394,C4395,C4396,C4397,C4400,C4401,C4402,C4403,C4408,C4409,C4410,C4411 |  |
| CAP CHIP 10UF 6.3V(+-20%,X6S,0402) | MURATA ERIE N.A. INC TAIWAN BRANCH Okayama Murata Mfg.Co., | GRM155C80J106M | 1 | C3627 | USB_BOM1 |
| CAP CHIP 0.1U 25V(+-10%,X7R,0402) | YAGEO CORPORATION | CC0402KRX7R8BB104 | 5 | C3628,C3629,C3631,C3632,C3633 | USB_BOM1 |
| CAP CHIP 1UF 25V(+-10%,X6S,0402) | MURATA ERIE N.A. INC TAIWAN BRANCH Okayama Murata Mfg.Co..Ltd.Wakura Murata Mfg. | GRM155C81E105K | 3 | C3630,C3634,C3637 | USB_BOM1 |
| CAP CHIP 100U 4V(+-20%,X6S,0805)MUR_FOR SEL | MURATA ERIE N.A. INC TAIWAN BRANCH Okayama Murata Mfg.Co.,Ltd.Wakura Murata Mfg. | GRM21BC80G107M | 16 | C4230,C4231,C4244,C4245,C4286,C4287,C4300,C4301,C4342,C4343,C4356,C4357,C4398,C4399,C4412,C4413 |  |
| CAP CHIP 1UF 25V(+-10%,X6S,0402) | MURATA ERIE N.A. INC TAIWAN BRANCH Okayama Murata Mfg.Co..Ltd.Wakura Murata Mfg. | GRM155C81E105K | 1 | C4493 | COMP_BOM1 |
| CAP CHIP 0.22U 25V(10%,X7R,0402) | TAIYO YUDEN CO.,LTD | TMK105B7224KV-FR | 9 | C4502,PC66,PC82,PC99,PC115,PC146,PC162,PC179,PC195 |  |
| LED SMD(2P) BLUE(LTST-C281TBKT-5A) | LITEON ELECTRONIC CO., LTD. | LTST-C281TBKT-5A | 14 | D1,D2,D3,D4,D7,D13,D14,D15,D16,D17,D18,D19,D20,D21 |  |
| DIODE SMD SDMK0340L-7-F(40V.30MA) | DIODES TAIWAN CO..LTD.(Kai Hong Shanghai) | SDMK0340L-7-F | 2 | D12,D23 |  |
| DIODE SMD 1N5819HW-7-F(40V.1A.SOD123) | "DIODES TAIWAN CO..LTD.(Kai Hong Shanghai)" | 1N5819HW-7-F | 1 | D24 |  |
| FUSE SMD 20A/125V(FAST,UL/CSA) | LITTELFUSE INC. | 0456020.ER | 1 | FS1 |  |
| BASE BOARD HANDLE S2W(FBS2W009,3A) |  | FBS2W00901 | 1 | HANDLE_0 |  |
| HANDLE EXP BD TOP F0T(FBF0T138,R3A)FVT |  | FBF0T13801 | 1 | HANDLE_1 |  |
| F0T BRACKET EXPANDER BD ASSY |  | 4SF0TRA000 | 4 | HS_BP0,HS_BP1,HS_BP2,HS_BP3 |  |
| CONN DIP HEADER 48P 4R MR(P2.54,H12.57) | AMPHENOL EAST ASIA LIMITED (Amphenol-TCS) (Shanghai | 10106263-6000001LF | 1 | J1 |  |
| CONN DIP HOUSING 260P 10R FR(P1.3,H32.3) | AMPHENOL EAST ASIA LIMITED (Amphenol-TCS) (Shanghai Amphenol | 10146445-101LF | 8 | J11,J12,J13,J14,J3,J5,J7,J9 |  |
| CONN SMD HEADER 3P 1R MS(P2.54,H9.65) | SAMTEC INC. | TSM-103-01-S-SV-TR | 9 | J19,J4,J55,J56,J57,J58,J59,J60,PJP1 |  |
| MINI JUMPER 2.54MM(5.0*2.4*6.0) BK |  | 57928-00211-V01 | 8 | J19_12,J4_12,J55_12,J56_12,J57_12,J58_12,J59_12,J60_12 |  |
| CONN SMD HOUSING 38P 2R FS(P0.6,H13.3) | AMPHENOL EAST ASIA LIMITED (Amphenol-TCS) (Shanghai Amphenol | U10DH3824103T | 1 | J2 |  |
| CONN SMD HOUSING 168P 2R FS(P0.6,H9.1) | AMPHENOL EAST ASIA LIMITED (Amphenol-TCS) (Shanghai Amphenol | G64V35313HR | 8 | J20,J21,J22,J23,J24,J25,J26,J27 |  |
| CONN SMD HOUSING 56P 2R FS(P0.6,H9.1) | AMPHENOL EAST ASIA LIMITED (Amphenol-TCS) (Shanghai Amphenol Airwave Communication Electronics Co.,Ltd) | ME1005610104011 | 16 | J30,J31,J32,J33,J34,J35,J36,J37,J38,J39,J40,J41,J42,J43,J44,J45 |  |
| CONN SMD HOUSING 56P 2R FR(P0.6,H20.125) | AMPHENOL EAST ASIA LIMITED (Amphenol-TCS) (Shanghai Amphenol Airwave Communication Electronics Co.,Ltd) | ME3005630501211 | 16 | J30_OTH,J31_OTH,J32_OTH,J33_OTH,J34_OTH,J35_OTH,J36_OTH,J37_OTH,J38_OTH,J39_OTH,J40_OTH,J41_OTH,J42_OTH,J43_OTH,J44_OTH,J45_OTH |  |
| CONN SMD MICRO USB 5P 1R FS(P0.65,H6.7) | MOLEX TAIWAN LTD.DONGGUAN MOLEX INTERCONNECT CO., LTD | 105133-0311 | 1 | J54 |  |
| CONN DIP HOUSING 3P 1R FR(H14.7) | AMPHENOL EAST ASIA LIMITED (Amphenol-TCS) (Shanghai Amphenol | 10165288-101LF | 4 | J61,J62,J63,J64 |  |
| CONN SMD HEADER 3P 1R MS(P2.54,H9.65) | SAMTEC INC. | TSM-103-01-S-SV-TR | 8 | J65,J66,J67,J68,J70,J71,J72,J73 | UART_BOM3 |
| CONN DIP HEADER 8P 1R MS(P2.54,H8.6) | PINREX TECHNOLOGY CORP | 210-HP1-080BR1 | 1 | JP2 |  |
| IC SOCKET SMD 16P(SPI,SOIC)(P1.27,H5.8) | LOTES(CHIA TSE TERMINAL INDUSTRYLOTES SUZHOU CO.,LTD | ACA-SPI-006-P07 | 4 | JPEX0,JPEX1,JPEX2,JPEX3 |  |
| IC FLASH(16P)W25Q256JWFIQ(SOIC) | WINBOND ELECTRONICS CORP. | W25Q256JWFIQ | 4 | JPEX0_FW1,JPEX1_FW1,JPEX2_FW1,JPEX3_FW1 |  |
| EMI FILTER BLM18PG121SN(120,2000MA) | MURATA ERIE N.A. INC TAIWAN BRANCH Okayama Murata Mfg.Co..Ltd. Wakura Murata Mfg | BLM18PG121SN1D | 4 | L1,L146,L147,L148 |  |
| EMI FILTER FCM2012KF-601T05(600,0.5A) | TAI-TECH ADVANCED ELECTRONICS CO. | FCM2012KF-601T05 | 6 | L8,L9,L10,L79,L80,L81 |  |
| EMI FILTER BLM18SG331TN1D(330,1.5A) | MURATA ERIE N.A. INC TAIWAN BRANCH Okayama Murata Mfg.Co.,Ltd.Wakura Murata Mfg | BLM18SG331TN1D | 2 | L11,L12 |  |
| EMI FILTER BLM18AG601SN1D(600.0.5A) | MURATA ERIE N.A. INC TAIWAN BRANCH Okayama Murata Mfg.Co., | BLM18AG601SN1D | 2 | L13,L14 |  |
| EMI FILTER FCM2012KF-601T05(600,0.5A) | TAI-TECH ADVANCED ELECTRONICS CO. | FCM2012KF-601T05 | 2 | L16,L149 |  |
| EMI FILTER BEAD BLM31SN500SN1L(50,10A) | MURATA ERIE N.A. INC TAIWAN BRANCH Okayama Murata Mfg.Co.,Ltd. | BLM31SN500SN1L | 32 | L27,L28,L29,L30,L47,L48,L49,L50,L61,L62,L63,L64,L75,L76,L77,L78,L82,L83,L84,L85,L98,L99,L100,L101,L114,L115,L116,L117,L130,L131,L132,L133 |  |
| EMI FILTER HCB2012KF-601T20(600,2000MA) | TAI-TECH ADVANCED ELECTRONICS CO. | HCB2012KF-601T20 | 40 | L88,L89,L90,L91,L92,L93,L94,L95,L96,L97,L104,L105,L106,L107,L108,L109,L110,L111,L112,L113,L120,L121,L122,L123,L124,L125,L126,L127,L128,L129,L136,L137,L138,L139,L140,L141,L142,L143,L144,L145 |  |
| SNLABEL_27X6 |  |  | 1 | ME9 |  |
| SNLABEL_15X5 |  |  | 1 | ME10 |  |
| OSC SMD 25MHZ(+-25PPM,3.3V)FJ2500009 | ECERA COMTEK CORPORATION (Pericom SaRonix Ecera Technology Corporation) P.S.E | FJ2500009 | 2 | OSC1,OSC2 |  |
| CAP CHIP 1UF 25V(+-10%,X6S,0402) | MURATA ERIE N.A. INC TAIWAN BRANCH Okayama Murata Mfg.Co..Ltd.Wakura Murata Mfg. | GRM155C81E105K | 6 | PC1,PC4,PC5,PC9,PC10,PC13 | HSC_BOM1 |
| CAP CHIP 0.01U 50V(+-10%,X7R,0402) | MURATA ERIE N.A. INC TAIWAN BRANCH Okayama Murata Mfg.Co.,Ltd. | WBM155R71H103K | 2 | PC2,PC3 | HSC_BOM1 |
| CAP CHIP 0.047U 25V(+-10% X7R 0402) | MURATA ERIE N.A. INC TAIWAN BRANCH Okayama Murata Mfg.Co.,Ltd.Wakura Murata Mfg. | GRM155R71E473K | 1 | PC6 | HSC_BOM1 |
| CAP CHIP 0.001U 50V(20%.X7R.0402) | ACER PERIPHERALS INC.(Darfon Electronics Corp.) | C1005X7R102MGT | 1 | PC7 | HSC_BOM1 |
| CAP CHIP 0.068UF 16V(+-10%.X7R 0402) | MURATA ERIE N.A. INC TAIWAN BRANCH Okayama Murata Mfg.Co..Ltd. Wakura Murata Mfg | GRM155R71C683K | 3 | PC8,PC12,PC15 | HSC_BOM1 |
| CAP CHIP 220P 50V(+-10%.X7R.0402) | "RTECH TECHNOLOGY CO..LTD.(Compostar)" | CC0402X221K3OST-S | 1 | PC11 | HSC_BOM1 |
| CAP CHIP 0.01U 25V(+-10%.X7R.0402) | ACER PERIPHERALS INC.(Darfon Electronics Corp.) | C1005X7R103KFT | 1 | PC19 |  |
| CAP OSCON SMD 270U 16V(20%,6.3*7.7)NPN | NIPPON CHEMI-CON | APXJ160ARA271MF80J | 6 | PC24,PC25,PC64,PC97,PC144,PC177 |  |
| CAP OSCON SMD 220U 6.3V(20%,5*5.8)NPN | NIPPON CHEMI-CON | APXF6R3ARA221ME611 | 2 | PC37,PC38 |  |
| CAP CHIP 56P 50V(+-5%.NPO.0402) | "MURATA ERIE N.A. INC TAIWAN BRANCH Okayama Murata Mfg.Co..Ltd.Wakura Murata Mfg | GRM1555C1H560J | 1 | PC39 |  |
| CAP CHIP 100NF 50V(+-10%,X7R,0402) | YAGEO CORPORATION | CC0402KRX7R9BB104 | 4 | PC44,PC47,PC124,PC128 |  |
| CAP CHIP 3300P 50V(+-10%.X7R.0402) | RTECH TECHNOLOGY CO..LTD.(Compostar) | CC0402X332K3OST | 4 | PC49,PC50,PC129,PC130 |  |
| CAP CHIP 470P,50V(+-5%,NPO,0402) | MURATA ERIE N.A. INC TAIWAN BRANCH Okayama Murata Mfg.Co.,Ltd. | GRM1555C1H471J | 4 | PC53,PC55,PC133,PC135 |  |
| CAP CHIP 2.2UF 10V(10%,X7S,0402) | MURATA ERIE N.A. INC TAIWAN BRANCH Okayama Murata Mfg.Co.,Ltd.Wakura Murata Mfg. | GRM155C71A225K | 16 | PC57,PC65,PC74,PC81,PC90,PC98,PC107,PC113,PC137,PC145,PC154,PC155,PC170,PC178,PC187,PC194 |  |
| CAP CHIP 22U 4V(+-20%,X6S,0805)MUR | MURATA ERIE N.A. INC TAIWAN BRANCH Okayama Murata Mfg.Co.,Ltd.Wakura Murata Mfg. | GRM21BC80G226M | 44 | PC68,PC69,PC70,PC84,PC85,PC86,PC101,PC102,PC103,PC117,PC120,PC121,PC148,PC149,PC150,PC164,PC167,PC168,PC181,PC182,PC183,PC197,PC198,PC199,PC212,PC213,PC214,PC215,PC232,PC233,PC234,PC235,PC252,PC253,PC254,PC255,PC272,PC273,PC274,PC275,PC291,PC292,PC293,PC294 |  |
| CAP CHIP 470U 2V(+-20%,SPCAP,7343)MAT | MATSUSHITA ELECTRONICS CORPORATION (PANASONIC)Wuxi Matsushita Battery Co., Ltd | EEFGX0D471R | 16 | PC71,PC72,PC87,PC88,PC104,PC105,PC118,PC119,PC151,PC152,PC165,PC169,PC184,PC185,PC200,PC201 |  |
| CAP OSCON SMD 390U 2.5V(20%,5*5.8)NPN | NIPPON CHEMI-CON | APXF2R5ARA391ME611 | 8 | PC217,PC218,PC238,PC239,PC258,PC259,PC278,PC279 |  |
| CAP CHIP 330P 50V(+-10%.X7R.0402) | RTECH TECHNOLOGY CO..LTD.(Compostar) | CC0402X331K3OST-S | 4 | PC219,PC240,PC260,PC280 |  |
| CAP CHIP 0.022U 25V(+-10%,X7R,0402) | WALSIN TECHNOLOGY CORPORATION | 0402B223K250CT | 12 | PC221,PC241,PC261,PC281,PC612,PC613,PC632,PC633,PC811,PC816,PC831,PC835 |  |
| CAP CHIP 150P 50V(+-5%.NPO.0402) | WALSIN TECHNOLOGY CORPORATION | 0402N151J500LT | 1 | PC297 |  |
| CAP CHIP 100P 50V(+-5%.X7R.0402) | PHYCOMP TAIWAN LTD.(YAGEO) | 2238 587 15509 | 41 | PC594,PC640,PC642,PC652,PC654,PC660,PC662,PC670,PC672,PC680,PC682,PC790,PC792,PC840,PC843,PC851,PC853,PC863,PC865,PC871,PC875,PC881,PC882,PC891,PC896,PC900,PC902,PC910,PC912,PC920,PC922,PC930,PC932,PC940,PC942,PC950,PC952,PC961,PC965,PC971,PC975 |  |
| CAP CHIP 39P 50V(+-5%,NPO,0402)MUR | MURATA ERIE N.A. INC TAIWAN BRANCH Okayama Murata Mfg.Co.,Ltd.Wakura Murata Mfg. | GRM1555C1H390J | 41 | PC596,PC641,PC644,PC651,PC653,PC664,PC666,PC674,PC676,PC684,PC686,PC794,PC795,PC842,PC845,PC852,PC855,PC860,PC862,PC870,PC874,PC880,PC885,PC890,PC893,PC904,PC906,PC914,PC916,PC924,PC926,PC934,PC936,PC944,PC946,PC954,PC956,PC960,PC964,PC970,PC974 |  |
| CAP CHIP 0.047U 25V(+-10% X7R 0402)MUR | MURATA ERIE N.A. INC TAIWAN BRANCH Okayama Murata Mfg.Co.,Ltd.Wakura Murata Mfg. | GRM155R71E473K | 25 | PC597,PC665,PC667,PC675,PC677,PC685,PC687,PC796,PC797,PC905,PC907,PC915,PC917,PC925,PC927,PC935,PC937,PC945,PC947,PC955,PC957,PC963,PC967,PC973,PC977 |  |
| CAP CHIP 2.2UF 16V(20%,X7R,0603) | TAIYO YUDEN CO.,LTD | EMK107BB7225MA-T | 8 | PC610,PC611,PC630,PC631,PC810,PC812,PC830,PC832 |  |
| CAP CHIP 0.22U 16V(10%.X7R.0402) | MURATA ERIE N.A. INC TAIWAN BRANCH Okayama Murata Mfg.Co..Ltd. Wakura Murata Mfg | GRM155R71C224K | 8 | PC614,PC616,PC634,PC636,PC813,PC815,PC833,PC836 |  |
| CAP CHIP 560P 50V(+-10%,X7R,0402) | MURATA ERIE N.A. INC TAIWAN BRANCH Okayama Murata Mfg.Co.,Ltd.Wakura Murata Mfg. | GRM155R71H561K | 8 | PC615,PC617,PC635,PC637,PC814,PC817,PC834,PC837 |  |
| CAP CHIP 0.01U 50V(+-10%,X7R,0402)MUR | MURATA ERIE N.A. INC TAIWAN BRANCH Okayama Murata Mfg.Co..Ltd.Wakura Murata Mfg. | WBM155R71H103K | 16 | PC646,PC647,PC656,PC657,PC846,PC847,PC850,PC857,PC866,PC867,PC873,PC877,PC884,PC887,PC895,PC897 |  |
| CAPCHIP 470U 2.5V(20%,SP,ESR4.5,7343)MAT | MATSUSHITA ELECTRONICS CORPORATION (PANASONIC)Wuxi Matsushita Battery Co., Ltd | EEFSX0E471E4 | 1 | PC1006 |  |
| DIODE SMD 5.0SMDJ14A(14V,216A,5000W) | LITTELFUSE INC. | 5.0SMDJ14A | 1 | PD1 |  |
| DIODE SMD SS15P3S-M3/86A(30V,15A) | SILICONIX TAIWAN LTD.(VISHAY SILICONIX ; VISHAY | SS15P3S-M3/86A | 1 | PD2 |  |
| DIODE TVS SMBJ14A(14V,25.9A,600W) | LITTELFUSE INC. | SMBJ14A | 24 | PD5,PD17,PD36,PD37,PD76,PD77,PD80,PD81,PD84,PD85,PD88,PD89,PD93,PD97,PD100,PD101,PD104,PD105,PD108,PD109,PD112,PD116,PD117,PD120 |  |
| DIODE SMD B340A-13-F(40V,3A)SCHOTTKY | DIODES TAIWAN CO.,LTD. | B340A-13-F | 24 | PD10,PD15,PD18,PD35,PD38,PD46,PD47,PD50,PD51,PD78,PD82,PD86,PD87,PD90,PD91,PD94,PD95,PD99,PD102,PD103,PD106,PD110,PD118,PD119 |  |
| IC(1932P)SS26-0B00-02(BGA)FABASN | BROADCOM CORPORATION(Altima) | SS26-0B00-02 | 4 | PEX0,PEX1,PEX2,PEX3 |  |
| IO HS 25F HP F0T(FBF0T002,3A)ART |  | FBF0T00201 | 4 | PEX0_HS,PEX1_HS,PEX2_HS,PEX3_HS |  |
| CONN SMD HEADER 3P 1R MS(P2.54,H9.3) | PINREX TECHNOLOGY CORP | 212-H91-03GBR1 | 1 | PJ1 | HSC_BOM1 |
| EMI FILTER BLM18SN220TN1D(22,8000MA) | MURATA ERIE N.A. INC TAIWAN BRANCH Okayama Murata Mfg.Co., | BLM18SN220TN1D | 6 | PL1,PL17,PL19,PL21,PL23,PL25 |  |
| IND SMD 10UH +-20%,4A(PCMB063T-100MS) | CYNTEC CO., LTD. | PCMB063T-100MS | 1 | PL2 |  |
| IND SMD 100NH 20% 16A(HCBS4545-101) | DELTA ELECTRONIC IND. CO., LTD. DELTA ELECTRONICS COMPONENT(WUJIANG)LTD | HCBS4545-101 | 5 | PL3,PL5,PL8,PL11,PL14 |  |
| IND SMD 1UH +-20% 29A(PCMC135T-1R0MF) | CYNTEC CO., LTD. | PCMC135T-1R0MF | 1 | PL4 |  |
| IND SMD 220NH 10% 61A(PGL6216.221HLT) | PULSE | PGL6216.221HLT | 8 | PL6,PL7,PL9,PL10,PL12,PL13,PL15,PL16 |  |
| IND SMD 0.33UH 20% 65A(MMD-12FD-R33M-V1Q | MAG. LAYERS (MAG.LAYERS Scientific-Technics Co., Ltd) | MMD-12FD-R33M-V1Q | 4 | PL18,PL20,PL22,PL24 |  |
| IND SMD 2.2UH +-20% 8A(PCMC063T-2R2MN) | CYNTEC CO.. LTD. | PCMC063T-2R2MN | 1 | PL26 |  |
| RES CHIP 0 1/16W +-5%(0402)EF | WALSIN TECHNOLOGY CORPORATION | WR04X000PTR | 18 | PR1,PR4,PR17,PR21,PR26,PR28,PR29,PR30,PR31,PR35,PR37,PR38,PR39,PR40,R492,R493,R6251,R6600 | HSC_BOM1 |
| RES CHIP 75K 1/16W +-1%(0402)EF | WALSIN TECHNOLOGY CORPORATION | WR04X7502FTR | 2 | PR2,PR3 | HSC_BOM1 |
| RES CHIP 4.99K 1/16W +-1%(0402)EF | WALSIN TECHNOLOGY CORPORATION | WR04X4991FTR | 2 | PR5,PR6 | HSC_BOM1 |
| RES CHIP 10K 1/16W +-1%(0402)EF | WALSIN TECHNOLOGY CORPORATION | WR04X1002FTR | 3 | PR7,PR14,PR16 | HSC_BOM1 |
| RES CHIP 1K 1/16W +-1%(0402)EF | WALSIN TECHNOLOGY CORPORATION | WR04X1001FTR | 2 | PR8,R6247 | HSC_BOM1 |
| RES CHIP 499 1/10W +-1%(0603)EF | YAGEO CORPORATION | RC0603FR-07499RP | 4 | PR9,PR10,PR12,PR18 |  |
| RES CHIP 120K 1/16W +-1%(0402)EF | YAGEO CORPORATION | RC0402FR-07120KP | 3 | PR11,PR27,PR36 | HSC_BOM1 |
| RES CHIP 2K 1/16W +-1%(0402)EF | WALSIN TECHNOLOGY CORPORATION | WR04X2001FTR | 6 | PR13,PR15,PR33,PR34,PR42,PR43 | HSC_BOM1 |
| RES CHIP 147K 1/16W +-1%(0402)EF | WALSIN TECHNOLOGY CORPORATION | WR04X1473FTR | 1 | PR57 |  |
| RES CHIP 28K 1/16W +-1%(0402)EF | YAGEO CORPORATION | RC0402FR-0728KP | 1 | PR58 |  |
| RES CHIP 56K 1/16W +-0.1%(0402) | YAGEO CORPORATION | RT0402BRD0756KL | 1 | PR61 |  |
| RES CHIP 6.19K 1/16W +-1%(0402)EF | WALSIN TECHNOLOGY CORPORATION | WR04X6191FTR | 2 | PR62,R3147 |  |
| RES CHIP 12.4K 1/16W +-0.1%( 0402)EF | WALSIN TECHNOLOGY CORPORATION | WF04H1242BTR | 1 | PR63 |  |
| RES CHIP 1 1/16W +-5%(0402)EF | WALSIN TECHNOLOGY CORPORATION | WR04X1R0 JTR | 2 | PR65,PR116 |  |
| RES CHIP 0 1/16W +-5%(0402)EF | WALSIN TECHNOLOGY CORPORATION | WR04X000PTR | 960 | PR69,PR73,PR77,PR80,PR84,PR90,PR92,PR95,PR97,PR101,PR105,PR109,PR113,PR126,PR129,PR133,PR139,PR144,PR146,PR150,PR154,PR158,PR162,PR7132,PR7133,PR7134,PR7135,PR7136,PR7137,PR7138,PR7139,PR7141,PR7143,PR7166,PR7167,PR7168,PR7169,PR7171,PR7172,PR7173,PR7174,PR7175,PR7178,PR7180,PR7182,R1,R2,R3,R4,R30,R32,R34,R37,R39,R40,R41,R42,R52,R53,R54,R55,R81,R83,R85,R88,R90,R91,R92,R93,R103,R104,R105,R106,R132,R134,R136,R139,R141,R142,R143,R144,R154,R155,R156,R157,R183,R185,R187,R190,R192,R193,R194,R195,R205,R206,R207,R208,R234,R236,R238,R241,R243,R244,R245,R246,R256,R257,R258,R259,R285,R287,R289,R292,R294,R295,R296,R297,R307,R308,R309,R310,R336,R338,R340,R343,R345,R346,R347,R348,R358,R359,R360,R361,R387,R389,R391,R394,R396,R397,R398,R399,R461,R462,R463,R464,R465,R466,R467,R468,R469,R470,R471,R503,R509,R511,R512,R520,R522,R523,R530,R533,R534,R541,R544,R545,R552,R555,R556,R565,R566,R567,R576,R577,R578,R587,R588,R589,R596,R599,R600,R607,R610,R611,R618,R621,R622,R629,R632,R633,R642,R643,R644,R653,R654,R655,R662,R665,R666,R674,R676,R677,R684,R688,R695,R698,R699,R706,R709,R710,R717,R720,R721,R728,R731,R732,R740,R742,R743,R750,R753,R754,R761,R765,R772,R776,R783,R786,R787,R795,R797,R798,R805,R808,R809,R817,R819,R820,R824,R826,R827,R830,R832,R834,R835,R838,R840,R842,R844,R846,R848,R851,R903,R906,R933,R935,R936,R946,R949,R952,R955,R958,R961,R966,R970,R985,R987,R997,R999,R1000,R1001,R1005,R1006,R1007,R1008,R1010,R1045,R1071,R1072,R1073,R1074,R1075,R1076,R1094,R1095,R1096,R1097,R1098,R1099,R1100,R1101,R1102,R1103,R1105,R1106,R1107,R1108,R1109,R1110,R1112,R1113,R1114,R1115,R1116,R1117,R1136,R1137,R1138,R1139,R1140,R1141,R1142,R1143,R1144,R1145,R1146,R1147,R1148,R1149,R1150,R1151,R1170,R1171,R1172,R1173,R1174,R1175,R1176,R1177,R1178,R1179,R1180,R1181,R1182,R1183,R1184,R1185,R1218,R1219,R1255,R1322,R1391,R1458,R1466,R1467,R1468,R1469,R1470,R1475,R1498,R1499,R1500,R1501,R1502,R1503,R1504,R1505,R1542,R1545,R1548,R1550,R1573,R1575,R1576,R1577,R1578,R1579,R1580,R1581,R1582,R1583,R1584,R1585,R1586,R1587,R1588,R1589,R1590,R1613,R1615,R1616,R1617,R1618,R1619,R1620,R1621,R1622,R1623,R1624,R1625,R1626,R1627,R1628,R1629,R1630,R1765,R1766,R1769,R1770,R1772,R1773,R1774,R1777,R1778,R1783,R1802,R1822,R1824,R1825,R1826,R1827,R1828,R1829,R1830,R1833,R1834,R1835,R1836,R1837,R1838,R1839,R1840,R1841,R1842,R1843,R1845,R1846,R1847,R1848,R1849,R1851,R1852,R1853,R1856,R1870,R2464,R2466,R2468,R2470,R2472,R2474,R2476,R2478,R2739,R2966,R2988,R3059,R3107,R3144,R3149,R3153,R3287,R3288,R3289,R3290,R3291,R3292,R3293,R3294,R3295,R3365,R3366,R3367,R3368,R3369,R3394,R3395,R3396,R3397,R3398,R3399,R3400,R3401,R3402,R3404,R3405,R3406,R3408,R3409,R3434,R3435,R3445,R3446,R3447,R3448,R3449,R3450,R3451,R3452,R3453,R3454,R3455,R3456,R3460,R3461,R3462,R3463,R3464,R3465,R3470,R3471,R3472,R3473,R3474,R3475,R3479,R3480,R3481,R3482,R3483,R3484,R3489,R3490,R3491,R3492,R3493,R3494,R3498,R3499,R3500,R3501,R3502,R3503,R3521,R3523,R3525,R3527,R3535,R3537,R3539,R3540,R3541,R3549,R3552,R3554,R3555,R3556,R3564,R3566,R3568,R3570,R3576,R3578,R3580,R3581,R3582,R3583,R3584,R3586,R3592,R3593,R3594,R3595,R3596,R3597,R3598,R3599,R3880,R3883,R3884,R3885,R3886,R3892,R3894,R3926,R3928,R3930,R3931,R3932,R3938,R3940,R3947,R3948,R3971,R3973,R3975,R3976,R3977,R3983,R3984,R3986,R3990,R3992,R3994,R3995,R3996,R4002,R4003,R4005,R4051,R4052,R4057,R4059,R4061,R4063,R4065,R4067,R4069,R4071,R4073,R4075,R4077,R4079,R4081,R4083,R4092,R4093,R4094,R4095,R4096,R4097,R4105,R4106,R4109,R4115,R4116,R4117,R4118,R4119,R4120,R4121,R4122,R4123,R4124,R4125,R4126,R4127,R4128,R4129,R4130,R4131,R4132,R4133,R4134,R4135,R4136,R4137,R4138,R4139,R4140,R4141,R4142,R4143,R4144,R4145,R4146,R4163,R4164,R4166,R4168,R4169,R4170,R4171,R4172,R4173,R4174,R4185,R4217,R4218,R4233,R4263,R4264,R4298,R4299,R4300,R4301,R4386,R4387,R4388,R4389,R4390,R4429,R4430,R4435,R4436,R4437,R4438,R4439,R4514,R4515,R4516,R4517,R4518,R4519,R4520,R4521,R4522,R4523,R4524,R4525,R4526,R4527,R4528,R4529,R4536,R4537,R4538,R4539,R4540,R4541,R4542,R4543,R4556,R4862,R4891,R4892,R5285,R5288,R5289,R5290,R5292,R5293,R5294,R5295,R5296,R5472,R5494,R5500,R5501,R5502,R5538,R5539,R5541,R5543,R5544,R5546,R5547,R5549,R5550,R5552,R5553,R5555,R5556,R5558,R5559,R5561,R5562,R5564,R5565,R5567,R5568,R5570,R5571,R5573,R5574,R5576,R5577,R5579,R5580,R5582,R5583,R5585,R5586,R5587,R5602,R5603,R5621,R5622,R5623,R5624,R5627,R5642,R5643,R5644,R5645,R5650,R5654,R5658,R5662,R5666,R5670,R5674,R5678,R5682,R5686,R5690,R5694,R5698,R5702,R5706,R5710,R5715,R5774,R5778,R5779,R5780,R5808,R5818,R5819,R5824,R5826,R5830,R5831,R5832,R5833,R5834,R5835,R5838,R5839,R5844,R5845,R5848,R5849,R5854,R5855,R5858,R5859,R5866,R5867,R5870,R5871,R5878,R5879,R5882,R5883,R5890,R5894,R5895,R5896,R5897,R5898,R5899,R5900,R5901,R5902,R5903,R5904,R5905,R5906,R5907,R5908,R5909,R5910,R5954,R5955,R5958,R5959,R5966,R5967,R5968,R5969,R5970,R5971,R5974,R5975,R5980,R5981,R5984,R5985,R5990,R5991,R5994,R5995,R6000,R6001,R6004,R6005,R6010,R6011,R6014,R6015,R6020,R6021,R6024,R6025,R6030,R6031,R6034,R6035,R6042,R6043,R6046,R6047,R6054,R6055,R6058,R6059,R6066,R6067,R6070,R6071,R6078,R6079,R6082,R6083,R6090,R6091,R6094,R6095,R6102,R6103,R6106,R6107,R6114,R6115,R6118,R6119,R6147,R6161,R6162,R6165,R6168,R6171,R6215,R6241,R6243,R6256,R6277,R6278,R6279,R6280,R6284,R6315,R6361,R6366,R6367,R6406,R6407,R6408,R6416,R6417,R6418,R6419,R6420,R6421,R6422,R6423,R6426,R6429,R6434,R6435,R6440,R6441,R6446,R6447,R6569,R6570,R6572,R6576,R6578,R6582,R6584,R6588,R6645,R6646,R6660,R6718,R6720,R6722,R6770,R6771,R6772,R6773,R6774,R6775,R6804,R4103,R4104,R3390,R3391,R3392 |  |
| RES CHIP 49.9 1/16W +-1%(0402)EF | WALSIN TECHNOLOGY CORPORATION | WR04X49R9FTR | 21 | PR76,PR78,PR79,PR81,PR125,PR127,PR128,PR130,R1260,R1327,R1396,R1463,R2978,R2979,R2980,R2981,R2982,R2983,R2984,R2985,R3762 |  |
| RES CHIP 1K 1/16W +-1%(0402)EF | WALSIN TECHNOLOGY CORPORATION | WR04X1001FTR | 228 | PR83,PR85,PR124,PR132,PR134,PR7131,R5,R6,R7,R8,R11,R13,R44,R49,R56,R57,R58,R59,R62,R64,R95,R100,R107,R108,R109,R110,R113,R115,R146,R151,R158,R159,R160,R161,R164,R166,R197,R202,R209,R210,R211,R212,R215,R217,R248,R253,R260,R261,R262,R263,R266,R268,R299,R304,R311,R312,R313,R314,R317,R319,R350,R355,R362,R363,R364,R365,R368,R370,R401,R406,R489,R490,R496,R825,R831,R833,R839,R1002,R1111,R1153,R1154,R1161,R1165,R1167,R1168,R1186,R1187,R1188,R1189,R1190,R1193,R1195,R1196,R1199,R1203,R1204,R1216,R1234,R1264,R1270,R1271,R1278,R1280,R1282,R1283,R1285,R1286,R1287,R1288,R1289,R1292,R1293,R1294,R1295,R1296,R1297,R1299,R1301,R1309,R1331,R1337,R1338,R1345,R1347,R1349,R1350,R1352,R1353,R1354,R1355,R1356,R1359,R1360,R1361,R1362,R1363,R1364,R1366,R1368,R1377,R1400,R1406,R1407,R1414,R1416,R1418,R1419,R1421,R1422,R1423,R1424,R1425,R1428,R1429,R1430,R1431,R1432,R1433,R1435,R1437,R1445,R1446,R1806,R3437,R3438,R3466,R3467,R3485,R3486,R3504,R3505,R5503,R5540,R5542,R5545,R5548,R5551,R5554,R5557,R5560,R5563,R5566,R5569,R5572,R5575,R5578,R5581,R5584,R5592,R5593,R5595,R5605,R5606,R5712,R5731,R5733,R5735,R5737,R5739,R5741,R5743,R5745,R5747,R5749,R5751,R5753,R5755,R5757,R5759,R5761,R5803,R5811,R5813,R5821,R5917,R5918,R6157,R6158,R6159,R6160,R6283,R6589,R6591,R6593,R6594,R4113,R4114,R4550 |  |
| RES CHIP 10K 1/16W +-1%(0402)EF | WALSIN TECHNOLOGY CORPORATION | WR04X1002FTR | 273 | PR94,PR143,PR6870,PR6871,PR6873,PR6874,PR6877,PR6878,PR6893,PR6894,PR6896,PR6898,PR6901,PR6902,PR6907,PR6908,PR6913,PR6914,PR7028,PR7029,PR7033,PR7035,PR7036,PR7038,PR7052,PR7053,PR7057,PR7058,PR7059,PR7062,PR7067,PR7068,PR7073,PR7074,PR7079,PR7080,PR7085,PR7086,PR7091,PR7092,PR7097,PR7098,R12,R23,R24,R50,R63,R74,R75,R101,R114,R125,R126,R152,R165,R176,R177,R203,R216,R227,R228,R254,R267,R278,R279,R305,R318,R329,R330,R356,R369,R380,R381,R407,R475,R486,R501,R823,R841,R843,R845,R847,R849,R902,R904,R945,R947,R951,R953,R957,R959,R1009,R1077,R1244,R1245,R1311,R1312,R1380,R1381,R1447,R1448,R2740,R3148,R3943,R3944,R3945,R3946,R4219,R4404,R4433,R4859,R4861,R5440,R5474,R5493,R5601,R5777,R5806,R5816,R5817,R5825,R5827,R5828,R5829,R5836,R5837,R5840,R5841,R5846,R5847,R5850,R5851,R5856,R5857,R5860,R5861,R5862,R5863,R5864,R5865,R5868,R5869,R5872,R5873,R5874,R5875,R5876,R5877,R5880,R5881,R5884,R5885,R5886,R5887,R5888,R5889,R5956,R5957,R5960,R5961,R5962,R5963,R5964,R5965,R5972,R5973,R5976,R5977,R5982,R5983,R5986,R5987,R5992,R5993,R5996,R5997,R6002,R6003,R6006,R6007,R6012,R6013,R6016,R6017,R6022,R6023,R6026,R6027,R6032,R6033,R6036,R6037,R6038,R6039,R6040,R6041,R6044,R6045,R6048,R6049,R6050,R6051,R6052,R6053,R6056,R6057,R6060,R6061,R6062,R6063,R6064,R6065,R6068,R6069,R6072,R6073,R6074,R6075,R6076,R6077,R6080,R6081,R6084,R6085,R6086,R6087,R6088,R6089,R6092,R6093,R6096,R6097,R6098,R6099,R6100,R6101,R6104,R6105,R6108,R6109,R6110,R6111,R6112,R6113,R6116,R6117,R6120,R6121,R6122,R6123,R6124,R6125,R6255,R6568,R6575,R6581,R6587,R6826,R6827,R6828,R6829,R6830,R6831,R6832,R6833,R6834,R6835,R6836,R6837,R6838,R6839,R6840,R6841 |  |
| RES CHIP 40.2K 1/16W +-1%(0402)EF | WALSIN TECHNOLOGY CORPORATION | WR04X4022FTR | 2 | PR96,PR145 |  |
| RES CHIP 2.2 1/16W +-1%(0402)EF | WALSIN TECHNOLOGY CORPORATION | WR04W2R20FTR | 8 | PR99,PR103,PR107,PR111,PR148,PR152,PR156,PR160 |  |
| RES CHIP 3.3 1/16W +-1%(0402)EF | YAGEO CORPORATION | RC0402FR-073R3P | 8 | PR100,PR104,PR108,PR112,PR149,PR153,PR157,PR161 |  |
| RES CHIP 11K 1/16W +-1%(0402)EF | WALSIN TECHNOLOGY CORPORATION | WR04X1102FTR | 8 | PR102,PR106,PR110,PR114,PR151,PR155,PR159,PR163 |  |
| RES CHIP 316 1/16W +-1%(0402)EF | WALSIN TECHNOLOGY CORPORATION | WR04X3160FTR | 1 | PR141 |  |
| RES CHIP 13K 1/16W +-1%(0402)EF | WALSIN TECHNOLOGY CORPORATION | WR04X1302FTR | 4 | PR166,PR171,PR176,PR181 |  |
| RES CHIP 6.04K 1/16W +-1%(0402)EF | YAGEO CORPORATION | RC0402FR-076K04P | 4 | PR167,PR172,PR177,PR182 |  |
| RES CHIP 12K 1/16W +-1%(0402)EF | WALSIN TECHNOLOGY CORPORATION | WR04X1202FTR | 10 | PR168,PR173,PR178,PR183,PR188,R4432,R6567,R6574,R6580,R6586 |  |
| RES CHIP 24K 1/16W +-1%(0402)EF | RALEC ELECTRONIC CO. | FTT022402FTH | 2 | PR186,R4434 |  |
| RES CHIP 10.7K 1/16W +-1%(0402)EF | WALSIN TECHNOLOGY CORPORATION | WR04X1072FTR | 1 | PR187 |  |
| RES CHIP 71.5K 1/16W +-1%(0402)EF | YAGEO CORPORATION | RC0402FR-0771K5P | 25 | PR6853,PR6915,PR6917,PR6919,PR6921,PR6923,PR6925,PR7011,PR7012,PR7099,PR7101,PR7103,PR7105,PR7107,PR7109,PR7111,PR7113,PR7115,PR7117,PR7119,PR7121,PR7123,PR7125,PR7127,PR7128 |  |
| RES CHIP 1.05K 1/16W +-1%(0402) | YAGEO CORPORATION | RC0402FR-071K05L | 1 | PR6854 |  |
| RES CHIP 49.9 1/10W +-1%(0603)EF | YAGEO CORPORATION | RC0603FR-0749R9P | 8 | PR6865,PR6867,PR6889,PR6891,PR7023,PR7030,PR7047,PR7054 |  |
| RES CHIP 120K 1/16W +-1%(0402)EF | YAGEO CORPORATION | RC0402FR-07120KP | 8 | PR6866,PR6868,PR6890,PR6892,PR7024,PR7031,PR7048,PR7055 |  |
| RES CHIP 20K 1/16W +-1%(0402)EF | WALSIN TECHNOLOGY CORPORATION | WR04X2002FTR | 9 | PR6869,PR6872,PR6895,PR6897,PR7027,PR7034,PR7051,PR7060,R502 |  |
| RES CHIP 14.7K 1/16W +-1% (0402) | CYNTEC CO.. LTD. | RR0510S-1472-FN | 8 | PR6875,PR6876,PR6899,PR6900,PR7032,PR7037,PR7056,PR7061 |  |
| RES CHIP 280K 1/16W +-1%(0402)EF | YAGEO CORPORATION | RC0402FR-07280KP | 16 | PR6903,PR6904,PR6909,PR6911,PR7063,PR7065,PR7069,PR7070,PR7075,PR7077,PR7081,PR7083,PR7087,PR7089,PR7093,PR7095 |  |
| RES CHIP 825 1/16W +-1% (0402) EF | YAGEO CORPORATION | RC0402FR-07825RP | 24 | PR6905,PR6906,PR6910,PR6912,PR7064,PR7066,PR7071,PR7072,PR7076,PR7078,PR7082,PR7084,PR7088,PR7090,PR7094,PR7096,R6307,R6309,R6311,R6313,R6306,R6308,R6310,R6312 |  |
| RES CHIP 1.33K 1/16W +-1%(0402)EF | WALSIN TECHNOLOGY CORPORATION | WR04X1331FTR | 8 | PR6916,PR6918,PR7013,PR7014,PR7100,PR7102,PR7104,PR7106 |  |
| RES CHIP 2.49K 1/16W +-1%(0402)EF | WALSIN TECHNOLOGY CORPORATION | WR04X2491FTR | 16 | PR6920,PR6922,PR6924,PR6926,PR7108,PR7110,PR7112,PR7114,PR7116,PR7118,PR7120,PR7122,PR7124,PR7126,PR7129,PR7130 |  |
| IC(45P)MP5990GMA-2222-Z(LGA) | Monolithic Power Systems, Inc (MPS International Ltd.) | MP5990GMA-2222-Z | 1 | PU1 | HSC_BOM1 |
| IC(32P)MP5991GLU-Z(LGA) | Monolithic Power Systems, Inc (MPS International Ltd.) | MP5991GLU-Z | 2 | PU2,PU3 | HSC_BOM1 |
| IC OTHER(8P) RT7251BZQW (WDFN-8L) | RICHTEK TECHNOLOGY CORPORATION | RT7251BZQW | 1 | PU4 |  |
| IC(21P)RS53319LR(QFN) | Reed Semiconductor Corporation | RS53319LR | 5 | PU5,PU16,PU17,PU18,PU19 |  |
| PROG IC(41P)ISL69259IRAZ-T(8B13EF75) | Renesas Technology Taiwan Co., Ltd. | ISL69259IRAZ-T | 2 | PU6,PU11 |  |
| IC CTRL(41P)ISL99380FRZ-TR5935(QFN) | Renesas Technology Taiwan Co., Ltd. | ISL99380FRZ-TR5935 | 8 | PU7,PU8,PU9,PU10,PU12,PU13,PU14,PU15 |  |
| IC(21P)RS53318LR(QFN) | Reed Semiconductor Corporation | RS53318LR | 1 | PU20 |  |
| IC (10P) MP5016GQH-L-Z(QFN) | Monolithic Power Systems, Inc (MPS International Ltd.) | MP5016GQH-L-Z | 41 | PU70,PU75,PU76,PU77,PU78,PU79,PU80,PU81,PU82,PU83,PU84,PU101,PU102,PU107,PU108,PU109,PU110,PU111,PU112,PU113,PU114,PU115,PU116,PU117,PU118,PU119,PU120,PU121,PU122,PU123,PU124,PU125,PU126,PU127,PU128,PU129,PU130,PU131,PU132,PU133,PU134 |  |
| IC(22P)RS31312R(QFN) | Reed Semiconductor Corporation | RS31312R | 8 | PU71,PU72,PU73,PU74,PU103,PU104,PU105,PU106 |  |
| TRANS MOSFET BSS138BKS(60V,0.32A,0.445W) | NXP semiconductors | BSS138BKS | 65 | Q113,Q119,Q120,Q121,Q122,Q126,Q127,Q128,Q129,Q12,Q130,Q133,Q134,Q135,Q136,Q14,Q15,Q19,Q200,Q201,Q202,Q203,Q204,Q205,Q206,Q207,Q208,Q209,Q20,Q210,Q211,Q212,Q213,Q214,Q215,Q216,Q217,Q218,Q219,Q220,Q221,Q222,Q223,Q224,Q225,Q226,Q227,Q228,Q229,Q230,Q231,Q232,Q233,Q234,Q235,Q236,Q237,Q238,Q239,Q242,Q243,Q244,Q245,Q246,Q247 |  |
| TRANS MOSFET DMN53D0LDW(50V,0.36A,0.31W) | DIODES TAIWAN CO.,LTD. | DMN53D0LDW-7 | 10 | Q123,Q1,Q2,Q3,Q4,Q58,Q5,Q6,Q7,Q8 |  |
| TRANMOS 2N7002KW SOT323(60V, 115MA,0.2W) | PAN JIT INTERNATIONAL INC. | 2N7002KW | 1 | Q124 |  |
| TRANMOS 2N7002KW SOT323(60V, 115MA,0.2W) | PAN JIT INTERNATIONAL INC. | 2N7002KW | 1 | Q125 | COMP_BOM1 |
| TRANS SMD MMBT3904(40V,0.2A,SOT-23) | PAN JIT INTERNATIONAL INC. | MMBT3904 | 2 | Q56,Q57 |  |
| TRANS MOS DMN3042L-7(30V,5.8A,0.72W) | DIODES TAIWAN CO.,LTD. | DMN3042L-7 | 2 | Q240,Q241 |  |
| RES CHIP 100K 1/16W +-1%(0402)EF | WALSIN TECHNOLOGY CORPORATION | WR04X1003FTR | 115 | R14,R15,R16,R17,R18,R19,R20,R21,R22,R38,R65,R66,R67,R68,R69,R70,R71,R72,R73,R89,R116,R117,R118,R119,R120,R121,R122,R123,R124,R140,R167,R168,R169,R170,R171,R172,R173,R174,R175,R191,R218,R219,R220,R221,R222,R223,R224,R225,R226,R242,R269,R270,R271,R272,R273,R274,R275,R276,R277,R293,R320,R321,R322,R323,R324,R325,R326,R327,R328,R344,R371,R372,R373,R374,R375,R376,R377,R378,R379,R395,R1003,R1022,R3146,R5522,R5651,R5655,R5659,R5663,R5668,R5671,R5676,R5679,R5684,R5687,R5692,R5695,R5700,R5703,R5708,R5711,R6177,R6179,R6253,R6296,R6297,R6298,R6299,R6300,R6301,R6305,R6314,R6411,R6415,R6448,R6714 |  |
| RES CHIP 100 1/16W +-1%(0402)EF | WALSIN TECHNOLOGY CORPORATION | WR04X1000FTR | 24 | R26,R28,R77,R79,R128,R130,R179,R181,R230,R232,R281,R283,R332,R334,R383,R385,R4554,R4555,R5799,R1831,R1832,R4547,R4548,R4549 |  |
| RES CHIP 33 1/16W +-1%(0402)EF | WALSIN TECHNOLOGY CORPORATION | WR04X33R0FTR | 268 | R36,R87,R138,R189,R240,R291,R342,R393,R500,R687,R764,R775,R828,R829,R836,R837,R929,R930,R941,R942,R980,R981,R991,R1476,R1487,R1489,R1490,R1491,R1492,R1493,R1494,R1495,R1496,R1497,R1574,R1614,R1767,R1768,R1771,R1775,R1776,R1779,R1780,R1788,R1789,R1794,R1795,R1797,R1800,R1807,R1808,R1815,R1816,R1817,R1818,R1819,R1820,R1821,R1864,R1865,R1866,R1867,R1868,R1869,R2537,R3304,R3305,R3306,R3307,R3308,R3309,R3310,R3311,R3605,R3616,R3624,R3632,R3640,R3648,R3761,R3879,R3891,R3893,R3929,R3937,R3939,R3974,R3982,R3985,R3993,R4001,R4004,R4087,R4091,R4107,R4108,R4110,R4232,R4268,R4302,R4303,R4304,R4305,R4306,R4307,R4308,R4309,R4893,R4894,R4895,R4898,R4900,R4901,R4902,R5278,R5279,R5297,R5298,R5299,R5300,R5588,R5646,R5647,R5649,R5653,R5657,R5661,R5665,R5669,R5673,R5677,R5681,R5685,R5689,R5693,R5697,R5701,R5705,R5709,R5716,R5718,R5719,R5720,R5721,R5722,R5727,R5732,R5734,R5736,R5738,R5740,R5742,R5744,R5746,R5748,R5750,R5752,R5754,R5756,R5758,R5760,R5762,R5763,R5764,R5765,R5766,R5767,R5768,R5769,R5770,R5771,R5772,R5773,R5800,R5801,R5802,R5809,R5891,R6227,R6244,R6268,R6303,R6304,R6386,R6387,R6388,R6390,R6392,R6393,R6394,R6396,R6397,R6398,R6400,R6401,R6402,R6404,R6405,R6659,R6661,R6662,R6663,R6664,R6665,R6666,R6667,R6668,R6679,R6686,R6692,R6698,R6704,R6710,R6717,R6719,R6721,R6799,R6800,R6802,R6803,R6805,R6806,R6807,R6808,R6809,R6810,R6811,R6812,R1483,R6269,R1465,R1693,R1694,R1707,R1708,R1721,R1722,R1735,R1736,R1637,R1638,R1651,R1652,R1665,R1666,R1679,R1680,R1695,R1696,R1709,R1710,R1723,R1724,R1737,R1738,R1639,R1640,R1653,R1654,R1667,R1668,R1681,R1682,R6359,R6358,R459,R460,R458 |  |
| RES CHIP 33.2 1/16W +-1%(0402)EF | WALSIN TECHNOLOGY CORPORATION | WR04X33R2FTR | 59 | R43,R45,R46,R47,R48,R51,R94,R96,R97,R98,R99,R102,R145,R147,R148,R149,R150,R153,R196,R198,R199,R200,R201,R204,R247,R249,R250,R251,R252,R255,R298,R300,R301,R302,R303,R306,R349,R351,R352,R353,R354,R357,R400,R402,R403,R404,R405,R408,R472,R2742,R3393,R4249,R4250,R4256,R4257,R4405,R5473,R5478,R6216 |  |
| RES CHIP 2.2K 1/16W +-5%(0402)EF | YAGEO CORPORATION | RC0402JR-072K2P | 25 | R60,R61,R111,R112,R1539,R1540,R1745,R1746,R1752,R1753,R1754,R1755,R1760,R1762,R5504,R6259,R6260,R6266,R6267,R9,R10,R162,R163,R4885,R4886 |  |
| RES CHIP 4.7K 1/16W +-1%(0402)EF | WALSIN TECHNOLOGY CORPORATION | WR04X4701FTR | 168 | R409,R412,R415,R418,R421,R424,R427,R430,R433,R436,R439,R442,R445,R448,R451,R454,R508,R510,R518,R521,R531,R542,R549,R554,R560,R561,R571,R582,R598,R606,R641,R650,R685,R686,R694,R696,R707,R718,R725,R730,R736,R737,R747,R759,R773,R774,R782,R784,R793,R796,R802,R803,R814,R875,R925,R926,R931,R932,R937,R938,R943,R964,R971,R972,R982,R983,R988,R989,R994,R995,R1004,R1032,R1033,R1034,R1035,R1040,R1041,R1042,R1043,R1261,R1328,R1397,R1464,R1781,R1782,R2463,R2465,R2467,R2469,R2471,R2473,R2475,R2477,R3442,R3459,R3478,R3497,R4047,R4054,R4055,R4056,R4058,R4060,R4062,R4064,R4066,R4068,R4070,R4072,R4074,R4076,R4078,R4080,R4082,R4330,R4331,R4332,R4333,R4334,R4335,R4336,R4337,R4346,R4347,R4348,R4349,R4350,R4351,R4352,R4353,R4359,R5893,R5916,R6153,R6154,R6155,R6156,R6219,R6220,R6257,R6425,R6428,R6431,R6433,R6437,R6439,R6443,R6445,R6669,R6670,R6671,R6672,R6673,R6674,R6675,R6676,R6677,R6678,R6683,R6684,R6689,R6690,R6695,R6696,R6701,R6702,R6707,R6708 |  |
| RES CHIP 10K 1/16W +-5%(0402)EF | WALSIN TECHNOLOGY CORPORATION | WR04X103 JTR | 107 | R410,R413,R417,R419,R422,R426,R429,R431,R435,R438,R441,R444,R446,R450,R453,R456,R1130,R1131,R1133,R1220,R1223,R1246,R1247,R1248,R1249,R1250,R1251,R1252,R1253,R1254,R1256,R1257,R1313,R1314,R1315,R1316,R1317,R1318,R1319,R1321,R1323,R1324,R1382,R1383,R1384,R1385,R1386,R1387,R1388,R1389,R1392,R1393,R1449,R1450,R1451,R1452,R1453,R1454,R1455,R1459,R1460,R1566,R1567,R1568,R1597,R1608,R1609,R1758,R1759,R1761,R2621,R2622,R3508,R3509,R3511,R3954,R3961,R3963,R3965,R4237,R4239,R4240,R4241,R4242,R4243,R4247,R4248,R4251,R4258,R4261,R4266,R4903,R6218,R6226,R6237,R6339,R6340,R6341,R6369,R6372,R6657,R6658,R6816,R6817,R6818,R6819,R6820 |  |
| RES CHIP 0 1/10W +-5% (0603)EF | WALSIN TECHNOLOGY CORPORATION | WR06X000PTR | 1 | R457 |  |
| RES CHIP 5.36K 1/16W +-1%(0402) | YAGEO CORPORATION | RC0402FR-075K36L | 1 | R473 |  |
| RES CHIP 2.87K 1/16W +-1%(0402)EF | WALSIN TECHNOLOGY CORPORATION | WR04X2871FTR | 2 | R474,R479 |  |
| RES CHIP 2K 1/16W +-1%(0402)EF | WALSIN TECHNOLOGY CORPORATION | WR04X2001FTR | 14 | R476,R477,R480,R4013,R4014,R4015,R4016,R4017,R4018,R4019,R4020,R4851,R5492,R6843 |  |
| RES CHIP 33 1/16W +-5%(0402)EF | WALSIN TECHNOLOGY CORPORATION | WR04X330 JTR | 6 | R487,R488,R1541,R1543,R1547,R1549 |  |
| RES CHIP 82K  1/16W +-1% (0402)EF | WALSIN TECHNOLOGY CORPORATION | WR04X8202FTR | 1 | R494 |  |
| RES CHIP 31.6K 1/16W +-1%(0402)EF | WALSIN TECHNOLOGY CORPORATION | WR04X3162FTR | 1 | R495 |  |
| RES CHIP 10 1/16W +-1%(0402)EF | WALSIN TECHNOLOGY CORPORATION | WR04X10R0FTR | 1 | R498 | COMP_BOM1 |
| RES CHIP 4.7K 1/16W +-5%(0402)EF | WALSIN TECHNOLOGY CORPORATION | WR04X472 JTR | 214 | R504,R515,R526,R537,R548,R559,R570,R581,R592,R603,R614,R625,R636,R647,R658,R669,R680,R691,R702,R713,R724,R735,R746,R757,R768,R779,R790,R801,R812,R1506,R1507,R1510,R1517,R1524,R1531,R1551,R1552,R1553,R1554,R1555,R1556,R1560,R1561,R1562,R1563,R1564,R1565,R1569,R1570,R1571,R1572,R1591,R1592,R1593,R1594,R1595,R1596,R1600,R1601,R1602,R1603,R1604,R1605,R1606,R1610,R1611,R1612,R1632,R1633,R1635,R1636,R1646,R1647,R1649,R1650,R1660,R1661,R1663,R1664,R1674,R1675,R1677,R1678,R1688,R1689,R1691,R1692,R1702,R1703,R1705,R1706,R1716,R1717,R1719,R1720,R1730,R1731,R1733,R1734,R1756,R1757,R1763,R1764,R1786,R1787,R1792,R1793,R1798,R1804,R1805,R1809,R1810,R1811,R3286,R3877,R3878,R3933,R3934,R3978,R3979,R3997,R3998,R4234,R4235,R4236,R4238,R4385,R4871,R4872,R4883,R4884,R4887,R4888,R5066,R5067,R5068,R5281,R5414,R5415,R5416,R5417,R5418,R5419,R5420,R5421,R5475,R5479,R5525,R5529,R5530,R5532,R5892,R5911,R5912,R5913,R6148,R6149,R6150,R6151,R6152,R6174,R6175,R6176,R6178,R6182,R6183,R6184,R6185,R6186,R6187,R6188,R6189,R6190,R6191,R6192,R6193,R6194,R6195,R6196,R6197,R6198,R6199,R6200,R6201,R6202,R6203,R6204,R6205,R6206,R6207,R6208,R6209,R6210,R6211,R6212,R6213,R6342,R6343,R6344,R6345,R6346,R6347,R6348,R6349,R6389,R6391,R6395,R6399,R6403,R6409,R6410,R6412,R6413,R6414 |  |
| RES CHIP 0.002 2W +-1%(2512)EF | WALSIN TECHNOLOGY CORPORATION | WW25RR002FTL | 29 | R506,R516,R527,R538,R551,R562,R573,R583,R593,R605,R615,R626,R638,R649,R661,R670,R682,R693,R704,R716,R727,R738,R748,R758,R770,R781,R792,R804,R815 |  |
| RES CHIP 10 1/16W +-1%(0402) | TA-I TECHNOLOGY CO..LTD. | RM04FTN10R0 | 58 | R513,R514,R524,R525,R535,R536,R546,R547,R557,R558,R568,R569,R579,R580,R590,R591,R601,R602,R612,R613,R623,R624,R634,R635,R645,R646,R656,R657,R667,R668,R678,R679,R689,R690,R700,R701,R711,R712,R722,R723,R733,R734,R744,R745,R755,R756,R766,R767,R777,R778,R788,R789,R799,R800,R810,R811,R821,R822 |  |
| RES CHIP 680 1/16W +-1%(0402)EF | YAGEO CORPORATION | RC0402FR-07680RP | 1 | R1019 |  |
| RES CHIP 1 1/10W +-1%(0603)EF | WALSIN TECHNOLOGY CORPORATION | WR06W1R00FTR | 17 | R1046,R1047,R1048,R1128,R1162,R1214,R4186,R4187,R4198,R5635,R5636,R5637,R5638,R5639,R5640,R5641,R6365 |  |
| RES CHIP 4.75K 1/16W +-1%(0402)EF | WALSIN TECHNOLOGY CORPORATION | WR04X4751FTR | 50 | R1056,R1059,R1060,R1061,R1062,R1063,R1064,R1066,R1067,R1068,R1069,R1070,R1078,R1079,R1080,R1081,R1120,R1122,R1123,R1125,R1221,R1258,R1259,R1325,R1326,R1394,R1395,R1461,R1462,R4191,R4201,R4203,R4204,R4206,R4207,R4208,R4209,R4210,R4221,R4222,R4223,R4227,R5491,R5781,R6164,R6167,R6170,R6173,R6370,R6371 |  |
| RES CHIP 2.2 1/10W +-1%(0603)EF | WALSIN TECHNOLOGY CORPORATION | WR06W2R20FTR | 2 | R1082,R1083 |  |
| RES CHIP 7.5 1/16W +-1%(0402) | YAGEO CORPORATION | RC0402FR-077R5L | 32 | R1084,R1085,R1087,R1088,R1089,R1090,R1091,R1092,R1205,R1206,R1207,R1208,R1209,R1210,R1211,R1212,R1225,R1226,R1227,R1228,R1229,R1230,R1231,R1232,R6374,R6375,R6376,R6377,R6378,R6379,R6380,R6382 |  |
| RES CHIP 22 1/16W +-1%(0402)EF | WALSIN TECHNOLOGY CORPORATION | WR04X22R0FTR | 18 | R1485,R4860,R3615,R3623,R3631,R3639,R3647,R4086,R4090,R3604,R993,R934,R965,R969,R984,R986,R996,R998 |  |
| RES CHIP 1.8K 1/16W +-1%(0402)EF | WALSIN TECHNOLOGY CORPORATION | WR04X1801FTR | 4 | R1743,R1744,R1747,R1748 |  |
| RES CHIP 100 1/16W +-5%(0402)EF | WALSIN TECHNOLOGY CORPORATION | WR04X101 JTR | 2 | R3006,R4857 |  |
| RES CHIP 51 1/16W +-5%(0402)EF | WALSIN TECHNOLOGY CORPORATION | WR04X510 JTR | 7 | R3546,R1472,R1471,R6384,R6385,R3407,R3403 |  |
| RES CHIP 267K 1/16W +-1%(0402)EF | WALSIN TECHNOLOGY CORPORATION | WR04X2673FTR | 2 | R4414,R4415 | COMP_BOM1 |
| RES CHIP 10K 1/16W +-1%(0402)EF | WALSIN TECHNOLOGY CORPORATION | WR04X1002FTR | 5 | R4416,R4417,R4418,R4419,R4420 | COMP_BOM1 |
| RES CHIP 0.51 1/16W +-1%(0402)EF | WALSIN TECHNOLOGY CORPORATION | WW04XR510FTR | 136 | R4558,R4559,R4560,R4561,R4562,R4563,R4564,R4565,R4566,R4567,R4568,R4569,R4570,R4571,R4572,R4573,R4574,R4575,R4576,R4577,R4578,R4579,R4580,R4581,R4582,R4583,R4584,R4585,R4586,R4587,R4588,R4589,R4590,R4591,R4592,R4593,R4594,R4595,R4596,R4597,R6449,R6450,R6451,R6452,R6453,R6454,R6455,R6456,R6457,R6458,R6459,R6460,R6461,R6462,R6463,R6464,R6465,R6466,R6469,R6470,R6471,R6472,R6473,R6474,R6475,R6476,R6477,R6478,R6479,R6480,R6483,R6484,R6485,R6486,R6487,R6488,R6491,R6492,R6493,R6494,R6495,R6496,R6499,R6500,R6501,R6502,R6503,R6504,R6505,R6506,R6507,R6508,R6509,R6510,R6513,R6514,R6515,R6516,R6517,R6518,R6521,R6522,R6523,R6524,R6525,R6526,R6529,R6530,R6531,R6532,R6533,R6534,R6535,R6536,R6537,R6538,R6539,R6540,R6543,R6544,R6545,R6546,R6547,R6548,R6551,R6552,R6553,R6554,R6555,R6556,R6559,R6560,R6561,R6562,R6563,R6564 |  |
| RES CHIP 15.8K 1/16W +-1% (0402)EF | WALSIN TECHNOLOGY CORPORATION | WR04X1582FTR | 1 | R4850 |  |
| RES CHIP 49.9K 1/16W +-1%(0402)EF | YAGEO CORPORATION | RC0402FR-0749K9P | 2 | R4852,R4853 |  |
| RES CHIP 0 1/16W +-5%(0402)EF | WALSIN TECHNOLOGY CORPORATION | WR04X000PTR | 9 | R5442,R5443,R5444,R5445,R5447,R5449,R5451,R5453,R6181 | USB_BOM1 |
| RES CHIP 680 1/16W +-1%(0402)EF | YAGEO CORPORATION | RC0402FR-07680RP | 1 | R5455 | USB_BOM1 |
| RES CHIP 100K 1/16W +-1%(0402)EF | WALSIN TECHNOLOGY CORPORATION | WR04X1003FTR | 1 | R5457 | USB_BOM1 |
| RES CHIP 10K 1/16W +-1%(0402)EF | WALSIN TECHNOLOGY CORPORATION | WR04X1002FTR | 1 | R5459 | USB_BOM1 |
| RES CHIP 107K 1/16W +-1%(0402)EF | YAGEO CORPORATION | RC0402FR-07107KP | 1 | R5495 |  |
| RES CHIP 10 1/16W +-1%(0402)EF | WALSIN TECHNOLOGY CORPORATION | WR04X10R0FTR | 1 | R5714 |  |
| RES CHIP 64.9K 1/16W +-1%(0402)EF | WALSIN TECHNOLOGY CORPORATION | WR04X6492FTR | 16 | R5842,R5843,R5852,R5853,R5978,R5979,R5988,R5989,R5998,R5999,R6008,R6009,R6018,R6019,R6028,R6029 |  |
| RES CHIP 22 1/16W +-1%(0402)EF | WALSIN TECHNOLOGY CORPORATION | WR04X22R0FTR | 3 | R6245,R6246,R6248 | HSC_BOM1 |
| RES CHIP 16.9K 1/16W +-1%(0402)EF | YAGEO CORPORATION | RC0402FR-0716K9P | 1 | R6249 | HSC_BOM1 |
| RES CHIP 6.19K 1/16W +-1%(0402)EF | WALSIN TECHNOLOGY CORPORATION | WR04X6191FTR | 1 | R6250 | HSC_BOM1 |
| RES CHIP 267K 1/16W +-1%(0402)EF | WALSIN TECHNOLOGY CORPORATION | WR04X2673FTR | 1 | R6252 |  |
| RES CHIP 15K 1/16W +-1%(0402)EF | WALSIN TECHNOLOGY CORPORATION | WR04X1502FTR | 4 | R6566,R6573,R6579,R6585 |  |
| RES CHIP 3K 1/16W +-1%(0402)EF | YAGEO CORPORATION | RC0402FR-073KP | 4 | R6590,R6592,R6595,R6596 |  |
| RES CHIP 0 1/16W +-5%(0402)EF | WALSIN TECHNOLOGY CORPORATION | WR04X000PTR | 16 | R6613,R6614,R6615,R6616,R6617,R6618,R6619,R6620,R6633,R6634,R6635,R6636,R6637,R6638,R6639,R6640 | UART_BOM3 |
| RES CHIP 0 1/16W +-5%(0402)EF | WALSIN TECHNOLOGY CORPORATION | WR04X000PTR | 1 | R6801 | CSOUT_BOM1 |
| RES CHIP 1K 1/16W +-1%(0402)EF | WALSIN TECHNOLOGY CORPORATION | WR04X1001FTR | 1 | R6825 | COMP_BOM1 |
| RES CHIP 1.5K 1/16W +-1%(0402)EF | WALSIN TECHNOLOGY CORPORATION | WR04X1501FTR | 1 | R6844 |  |
| SCREW M3.0*5.0-I(NI) (NYLOK)IRON |  | M30050I07 | 4 | SCREW_0,SCREW_1,SCREW_2,SCREW_3 |  |
| SCREW M3*7-I(ZN)STEEL |  | M30070I02 | 4 | SCREW_4,SCREW_5,SCREW_6,SCREW_7 |  |
| SCREW M1.6*4.5-P(NI,NYLOK,D3.2,T1.3)STL |  | MM16045P000 | 32 | SCREW_SSD0_1,SCREW_SSD0_2,SCREW_SSD10_1,SCREW_SSD10_2,SCREW_SSD11_1,SCREW_SSD11_2,SCREW_SSD12_1,SCREW_SSD12_2,SCREW_SSD13_1,SCREW_SSD13_2,SCREW_SSD14_1,SCREW_SSD14_2,SCREW_SSD15_1,SCREW_SSD15_2,SCREW_SSD1_1,SCREW_SSD1_2,SCREW_SSD2_1,SCREW_SSD2_2,SCREW_SSD3_1,SCREW_SSD3_2,SCREW_SSD4_1,SCREW_SSD4_2,SCREW_SSD5_1,SCREW_SSD5_2,SCREW_SSD6_1,SCREW_SSD6_2,SCREW_SSD7_1,SCREW_SSD7_2,SCREW_SSD8_1,SCREW_SSD8_2,SCREW_SSD9_1,SCREW_SSD9_2 |  |
| IC OTHER(100P)9SQ440NQQI8(QFN) | INTEGRATED DEVICE TECHNOLOGY,INC. | 9SQ440NQQI8 | 2 | U113,U117 |  |
| IC OTHER(8P) SN74LVC3G34DCTR(SSOP) | TEXAS INSTRUMENTS SUPPLY CO., | SN74LVC3G34DCTR | 8 | U305,U308,U309,U428,U425,U426,U427,U429 |  |
| IC EEPROM(8P) AT24C64D-SSHM-T(SOIC) | ATMEL | AT24C64D-SSHM-T | 1 | U7 |  |
| IC(5P) 74HC1G126GW(SOT353)EP | PHILIPS TAIWAN LTD., | 74HC1G126GW | 24 | U8,U13,U18,U23,U28,U33,U38,U43,U382,U383,U384,U385,U386,U387,U388,U389,U390,U391,U392,U393,U394,U395,U396,U397 |  |
| TRANS MOS BSS138K(50V,0.22A,0.35W) | FAIRCHILD SEMICONDUCTOR | BSS138K | 40 | U9,U14,U19,U24,U29,U34,U39,U44,U363,U364,U365,U366,U367,U368,U369,U370,U371,U372,U373,U374,U375,U376,U377,U378,U398,U399,U400,U401,U402,U403,U404,U405,U406,U407,U408,U409,U410,U411,U412,U413 |  |
| IC(5P) SN74LVC1G17DCKR (SC-70) | TEXAS INSTRUMENTS SUPPLY CO., | SN74LVC1G17DCKR | 8 | U10,U15,U20,U25,U30,U35,U40,U45 |  |
| IC(5P) 74LVC1G08GV (SC-74A) | PHILIPS TAIWAN LTD., | 74LVC1G08GV | 13 | U11,U16,U21,U26,U31,U36,U41,U46,U325,U327,U340,U360,U418 |  |
| IC(3P)DS1818R-5+/T&R(SOT23) | MAXIM JAPAN CO..LTD(DALLAS SEMICONDUCTOR CORP.) | DS1818R-5+/T&R | 8 | U12,U17,U22,U27,U32,U37,U42,U47 |  |
| IC OTHER(16P) SN74AVC4T774PWR(TSSOP) | TEXAS INSTRUMENTS SUPPLY CO., | SN74AVC4T774PWR | 2 | U50,U63 |  |
| IC(16P)ISL28022FRZ-T(QFN) | Renesas Technology Taiwan Co., Ltd. | ISL28022FRZ-T | 29 | U51,U54,U55,U56,U59,U60,U61,U62,U71,U72,U73,U74,U75,U76,U77,U78,U79,U80,U81,U82,U83,U84,U85,U86,U87,U90,U94,U95,U96 |  |
| IC OTHER(5P) SN74AUP1G32DBVR(SOT-23) | TEXAS INSTRUMENTS SUPPLY CO., | SN74AUP1G32DBVR | 2 | U52,U64 |  |
| IC(256P) AST1030A1-GP(TFBGA) | ASPEED Technology Inc. | AST1030A1-GP | 1 | U5 |  |
| IC OTHER(16P)PI3CH480QEX(QSOP) | PERICOM SEMICONDUCTOR CORPORATION | PI3CH480QEX | 4 | U65,U66,U67,U68 |  |
| PROG IC(484P)LCMXO3LF-9400C-5BG(0X51BB) | LATTICE SEMICONDUCTOR CORP., | LCMXO3LF-9400C-5BG484C | 1 | U6 |  |
| IC OTHER(8P)FSA3357K8X(US8) | FAIRCHILD SEMICONDUCTOR | FSA3357K8X | 2 | U88,U89 |  |
| IC(6P) SN74LVC2G07DCKR(SC70-6) | TEXAS INSTRUMENTS SUPPLY CO.. | SN74LVC2G07DCKR | 18 | U100,U101,U102,U103,U104,U105,U106,U107,U143,U144,U145,U146,U351,U352,U438,U439,U440,U441 |  |
| IC OTHER (4P) PRTR5V0U2X (SOT143B) | NXP semiconductors | PRTR5V0U2X | 1 | U108 |  |
| IC OTHERS(10P) PI3USB103ZLE(TQFN) | PERICOM SEMICONDUCTOR CORPORATION | PI3USB103ZLE | 1 | U110 |  |
| IC CTRL(28P) GL852G-OHY60(QFN) | Genesys Logic, Inc. (Genesys Logic America, Inc.) | GL852G-OHY60 | 1 | U112 |  |
| IC OTHER(80P)9QXL2001BNHGI8(GQFN) | INTEGRATED DEVICE TECHNOLOGY,INC. | 9QXL2001BNHGI8 | 1 | U114 |  |
| IC OTHER(48P)9ZXL0851EKILFT(VFQFPN) | INTEGRATED DEVICE TECHNOLOGY,INC. | 9ZXL0851EKILFT | 2 | U115,U116 |  |
| IC OTHER(32P) 9ZXL0451EKILFT(VFQFPN) | INTEGRATED DEVICE TECHNOLOGY,INC. | 9ZXL0451EKILFT | 2 | U118,U424 |  |
| IC OTHER(8P) PCA9509DP(TSSOP) | NXP semiconductors | PCA9509DP | 4 | U119,U120,U121,U122 |  |
| IC OTHER(8P) PCA9617ADP(TSSOP) | NXP semiconductors | PCA9617ADP | 23 | U123,U126,U127,U128,U129,U130,U131,U132,U133,U134,U135,U136,U137,U138,U139,U140,U141,U313,U314,U315,U316,U420,U421 |  |
| IC OTHER(24P) TCA9548APWR(TSSOP) | TEXAS INSTRUMENTS SUPPLY CO., | TCA9548APWR | 3 | U124,U125,U142 |  |
| IC OTHER(14P) 74CBTLV3126PW(TSSOP) | NXP semiconductors | 74CBTLV3126PW | 1 | U294 |  |
| IC OTHER(5P)SN74LVC1G126DCKR(SC70) | TEXAS INSTRUMENTS SUPPLY CO., | SN74LVC1G126DCKR | 2 | U302,U356 |  |
| IC OTHER(24P)PCA9555APW(TSSOP) | NXP semiconductors | PCA9555APW | 1 | U324 |  |
| IC OTHER (8P) LM75BD(SO8) | NXP semiconductors | LM75BD | 4 | U328,U329,U416,U417 |  |
| IC OTHER(24P)PCA9539RPW(TSSOP) | NXP semiconductors | PCA9539RPW | 2 | U330,U419 |  |
| IC OTHER(5P)SN74LVC1G07DCKR(SOT) | TEXAS INSTRUMENTS SUPPLY CO.. | SN74LVC1G07DCKR | 1 | U336 |  |
| IC OTHER(6P)LT6700CS6-1#TRPBF(TSOT-23) | LINEAR TECHNOLOGY CORPORATION | LT6700CS6-1#TRPBF | 1 | U338 | COMP_BOM1 |
| IC OTHER(10P) RT9059GQW(WDFN) | RICHTEK TECHNOLOGY CORPORATION | RT9059GQW | 5 | U342,U430,U431,U432,U433 |  |
| IC CTRL(28P) GL852G-OHY60(QFN) | Genesys Logic, Inc. (Genesys Logic America, Inc.) | GL852G-OHY60 | 1 | U353 | USB_BOM1 |
| IC OTHER(4P)ADM6315-29D3ARTZR7(SOT143) | ANALOG DEVICES | ADM6315-29D3ARTZR7 | 1 | U358 |  |
| IC OTHER(6P)ADM1085AKSZ-REEL7(SC70) | ANALOG DEVICES | ADM1085AKSZ-REEL7 | 1 | U359 | DELAY1_BOM1 |
| IC(5P) 74LVC1G07GW(SOT353) | PHILIPS TAIWAN LTD. | 74LVC1G07GW | 1 | U362 |  |
| IC(5P)SN74LVC1G07DBVR(SOT23) | TEXAS INSTRUMENTS SUPPLY CO.. | SN74LVC1G07DBVR | 1 | U415 |  |
| VR HS 24F EX F0T(FBF0T009,3A)ART |  | FBF0T00901 | 2 | VR_HS0,VR_HS1 |  |
| XTAL 12MHZ(+-20PPM,10PF)E2SB12E00000EE | HANGZHOU HOSONIC ELECTRONIC CO.,LTD (Hosonic Electronic Co., Ltd.) | E2SB12E00000EE | 1 | Y5 |  |
| XTAL SMD 25MHZ(+-10PPM,8PF)FL2500498 | DIODES TAIWAN CO.,LTD. | FL2500498 | 2 | Y6,Y7 |  |
| XTAL 12MHZ(+-20PPM,10PF)E2SB12E00000EE | HANGZHOU HOSONIC ELECTRONIC CO.,LTD (Hosonic Electronic Co., Ltd.) | E2SB12E00000EE | 1 | Y8 | USB_BOM1 |
| THUMB SCREW SMT F0C(FBF0C045,REV3A)FVT |  | FBF0C04501 | 23 | H46,H47,H48,H49,H50,H51,H52,H53,H54,H55,H56,H58,H59,H60,H61,H62,H63,H64,H67,H68,H69,H70,H71 |  |
| RES CHIP 75 1/16W +-1%(0402)EF | WALSIN TECHNOLOGY CORPORATION | WR04X75R0FTR | 1 | R6302 |  |
| RES CHIP 200 1/16W +-1%(0402)EF | WALSIN TECHNOLOGY CORPORATION | WR04X2000FTR | 8 | R1477,R1478,R1479,R1480,R1481,R1484,R1486,R1488 |  |
| RES CHIP 3.3K 1/16W +-1%(0402)EF | WALSIN TECHNOLOGY CORPORATION | WR04X3301FTR | 8 | R214,R265,R316,R367,R213,R264,R315,R366 |  |
